FILE_TYPE = MACRO_DRAWING;
SET COLOR_WIRE YELLOW;
SET COLOR_PROP MONO;
SET COLOR_DOT WHITE;
SET COLOR_ARC YELLOW;
SET COLOR_BODY GREEN;
SET COLOR_NOTE MONO;
SET PROP_DISPLAY VALUE;
SET PAGE_NUMBER P236;
FORCEADD OFFPAGE..2
(11350 4425);
FORCEPROP 2 LAST $XR0 235 
J 0
(11539 4425);
DISPLAY 0.638298 (11539 4425);
PAINT MONO (11539 4425);
FORCEPROP 2 LAST ROOM PVCCIO_CPU0
J 0
(10950 4500);
DISPLAY 3.127660 (10950 4500);
PAINT WHITE (10950 4500);
DISPLAY INVISIBLE (10950 4500);
FORCEPROP 2 LAST CDS_LIB mstr_standard
J 0
(11350 4425);
DISPLAY 1.617021 (11350 4425);
PAINT ORANGE (11350 4425);
DISPLAY INVISIBLE (11350 4425);
FORCEPROP 2 LAST BOM_COST PROC_VRD_PVCCIO_CPU0
J 0
(11550 4475);
DISPLAY 2.340426 (11550 4475);
PAINT WHITE (11550 4475);
DISPLAY INVISIBLE (11550 4475);
FORCEPROP 2 LAST PATH I1
J 0
(11550 4475);
DISPLAY 1.021277 (11550 4475);
PAINT ORANGE (11550 4475);
DISPLAY INVISIBLE (11550 4475);
FORCEPROP 1 LAST OFFPAGE TRUE
J 0
(11675 4300);
PAINT GREEN (11675 4300);
DISPLAY INVISIBLE (11675 4300);
FORCEPROP 1 LAST COMMENT_BODY TRUE
J 0
(11305 4330);
DISPLAY 2.787234 (11305 4330);
PAINT PEACH (11305 4330);
DISPLAY INVISIBLE (11305 4330);
FORCEADD INDUCTOR..1
(11150 3950);
FORCEPROP 1 LAST LOCATION L7A2
J 0
(11150 4000);
DISPLAY 0.617021 (11150 4000);
PAINT AQUA (11150 4000);
FORCEPROP 1 LASTPIN (11250 3950) $PN 2
J 2
(11260 3960);
DISPLAY 0.617021 (11260 3960);
PAINT WHITE (11260 3960);
FORCEPROP 1 LAST PART_NUMBER D92183-036
J 0
(11050 3900);
DISPLAY 0.617021 (11050 3900);
PAINT BLUE (11050 3900);
FORCEPROP 1 LAST VALUE 0.3UH
J 2
(11145 3865);
DISPLAY 0.617021 (11145 3865);
PAINT SKYBLUE (11145 3865);
FORCEPROP 1 LAST PACK_TYPE SM
J 0
(11140 3815);
DISPLAY 0.617021 (11140 3815);
PAINT SKYBLUE (11140 3815);
FORCEPROP 1 LAST MATERIAL IND
J 0
(11165 3865);
DISPLAY 0.617021 (11165 3865);
PAINT SKYBLUE (11165 3865);
FORCEPROP 1 LASTPIN (11050 3950) $PN 1
J 0
(11050 3960);
DISPLAY 0.617021 (11050 3960);
PAINT WHITE (11050 3960);
FORCEPROP 2 LAST SEC 1
J 0
(11074 4149);
DISPLAY 0.680851 (11074 4149);
PAINT MONO (11074 4149);
DISPLAY INVISIBLE (11074 4149);
FORCEPROP 2 LAST SEC_TYPE SM
J 0
(11074 4149);
DISPLAY 1.021277 (11074 4149);
PAINT ORANGE (11074 4149);
DISPLAY INVISIBLE (11074 4149);
FORCEPROP 1 LAST PATH I10
J 0
(11050 4100);
DISPLAY 0.978723 (11050 4100);
PAINT ORANGE (11050 4100);
DISPLAY INVISIBLE (11050 4100);
FORCEPROP 2 LAST ROOM PVNN_PCH_STBY
J 0
(11050 4050);
DISPLAY 2.212766 (11050 4050);
PAINT WHITE (11050 4050);
DISPLAY INVISIBLE (11050 4050);
FORCEPROP 2 LAST CDS_LIB mstr_discrete
J 0
(11150 3950);
PAINT ORANGE (11150 3950);
DISPLAY INVISIBLE (11150 3950);
FORCEPROP 2 LAST CDS_LOCATION L7A2
J 0
(11050 4000);
DISPLAY 0.617021 (11050 4000);
PAINT AQUA (11050 4000);
DISPLAY INVISIBLE (11050 4000);
FORCEADD GND..1
(10375 3575);
FORCEPROP 3 LASTPIN (10375 3625) SIG_NAME GND\g
J 0
(10385 3635);
DISPLAY 0.659574 (10385 3635);
PAINT MONO (10385 3635);
DISPLAY INVISIBLE (10385 3635);
FORCEPROP 1 LAST SIZE 1B
J 0
(10450 3525);
DISPLAY 2.787234 (10450 3525);
PAINT GREEN (10450 3525);
DISPLAY INVISIBLE (10450 3525);
FORCEPROP 2 LAST CDS_LIB mstr_symbols
J 0
(10375 3575);
DISPLAY 1.617021 (10375 3575);
PAINT ORANGE (10375 3575);
DISPLAY INVISIBLE (10375 3575);
FORCEPROP 1 LAST PATH I11
J 0
(10450 3575);
DISPLAY 0.872340 (10450 3575);
PAINT AQUA (10450 3575);
DISPLAY INVISIBLE (10450 3575);
FORCEPROP 1 LAST VOLTAGE 0.0V
J 0
(10330 3532);
DISPLAY 0.340426 (10330 3532);
PAINT SKYBLUE (10330 3532);
DISPLAY INVISIBLE (10330 3532);
FORCEPROP 2 LAST BOM_COST PROC_VRD_PVCCIO_CPU0
J 0
(10000 3650);
DISPLAY 2.340426 (10000 3650);
PAINT WHITE (10000 3650);
DISPLAY INVISIBLE (10000 3650);
FORCEPROP 2 LAST ROOM PVCCIO_CPU0
J 0
(9825 3650);
DISPLAY 3.127660 (9825 3650);
PAINT WHITE (9825 3650);
DISPLAY INVISIBLE (9825 3650);
FORCEPROP 1 LAST BODY_TYPE PLUMBING
J 0
(10330 3532);
DISPLAY 0.340426 (10330 3532);
PAINT GREEN (10330 3532);
DISPLAY INVISIBLE (10330 3532);
FORCEPROP 1 LAST HDL_POWER GND
J 0
(10375 3725);
DISPLAY 2.787234 (10375 3725);
PAINT GREEN (10375 3725);
DISPLAY INVISIBLE (10375 3725);
FORCEADD IR354XX..1
(9700 4250);
FORCEPROP 2 LASTPIN (9200 3950) $PN 33
J 2
(9190 3960);
DISPLAY 0.617021 (9190 3960);
PAINT ORANGE (9190 3960);
FORCEPROP 2 LASTPIN (9200 4050) $PN 39
J 2
(9190 4060);
DISPLAY 0.617021 (9190 4060);
PAINT ORANGE (9190 4060);
FORCEPROP 1 LAST VALUE IR35412
J 1
(9700 4875);
DISPLAY 0.617021 (9700 4875);
PAINT SKYBLUE (9700 4875);
FORCEPROP 2 LASTPIN (9200 3900) $PN 32
J 2
(9190 3910);
DISPLAY 0.617021 (9190 3910);
PAINT ORANGE (9190 3910);
FORCEPROP 2 LASTPIN (10200 4800) $PN 38
J 0
(10210 4810);
DISPLAY 0.617021 (10210 4810);
PAINT ORANGE (10210 4810);
FORCEPROP 2 LASTPIN (10200 4300) $PN 36
J 0
(10210 4310);
DISPLAY 0.617021 (10210 4310);
PAINT ORANGE (10210 4310);
FORCEPROP 2 LAST NO_XNET_CONNECTION 1
J 0
(9250 5100);
PAINT MONO (9250 5100);
FORCEPROP 1 LAST MATERIAL IC
J 0
(9250 5000);
DISPLAY 0.617021 (9250 5000);
PAINT SKYBLUE (9250 5000);
FORCEPROP 1 LAST LOCATION EU7A3
J 0
(9250 5050);
DISPLAY 0.617021 (9250 5050);
PAINT AQUA (9250 5050);
FORCEPROP 2 LASTPIN (9200 4750) $PN 30
J 2
(9190 4760);
DISPLAY 0.617021 (9190 4760);
PAINT ORANGE (9190 4760);
FORCEPROP 2 LASTPIN (9200 4700) $PN 25
J 2
(9190 4710);
DISPLAY 0.617021 (9190 4710);
PAINT ORANGE (9190 4710);
FORCEPROP 2 LASTPIN (9200 4600) $PN 4
J 2
(9190 4610);
DISPLAY 0.617021 (9190 4610);
PAINT ORANGE (9190 4610);
FORCEPROP 2 LASTPIN (9200 4800) $PN 3
J 2
(9190 4810);
DISPLAY 0.617021 (9190 4810);
PAINT ORANGE (9190 4810);
FORCEPROP 2 LASTPIN (9200 4400) $PN 1
J 2
(9190 4410);
DISPLAY 0.617021 (9190 4410);
PAINT ORANGE (9190 4410);
FORCEPROP 2 LASTPIN (9200 4500) $PN 35
J 2
(9190 4510);
DISPLAY 0.617021 (9190 4510);
PAINT ORANGE (9190 4510);
FORCEPROP 2 LASTPIN (9200 4250) $PN 6
J 2
(9190 4260);
DISPLAY 0.617021 (9190 4260);
PAINT ORANGE (9190 4260);
FORCEPROP 2 LASTPIN (9200 4300) $PN 41
J 2
(9190 4310);
DISPLAY 0.617021 (9190 4310);
PAINT ORANGE (9190 4310);
FORCEPROP 2 LASTPIN (9200 4150) $PN 34
J 2
(9190 4160);
DISPLAY 0.617021 (9190 4160);
PAINT ORANGE (9190 4160);
FORCEPROP 2 LASTPIN (10200 3800) $PN 40
J 0
(10210 3810);
DISPLAY 0.617021 (10210 3810);
PAINT ORANGE (10210 3810);
FORCEPROP 2 LASTPIN (10200 3750) $PN 7
J 0
(10210 3760);
DISPLAY 0.617021 (10210 3760);
PAINT ORANGE (10210 3760);
FORCEPROP 2 LASTPIN (10200 3700) $PN 5
J 0
(10210 3710);
DISPLAY 0.617021 (10210 3710);
PAINT ORANGE (10210 3710);
FORCEPROP 2 LASTPIN (10200 3850) $PN 2
J 0
(10210 3860);
DISPLAY 0.617021 (10210 3860);
PAINT ORANGE (10210 3860);
FORCEPROP 2 LASTPIN (10200 4600) $PN 37
J 0
(10210 4610);
DISPLAY 0.617021 (10210 4610);
PAINT ORANGE (10210 4610);
FORCEPROP 2 LASTPIN (10200 4550) $PN 31
J 0
(10210 4560);
DISPLAY 0.617021 (10210 4560);
PAINT ORANGE (10210 4560);
FORCEPROP 2 LASTPIN (10200 3950) $PN 10
J 0
(10210 3960);
DISPLAY 0.617021 (10210 3960);
PAINT ORANGE (10210 3960);
FORCEPROP 1 LAST PART_NUMBER H73684-001
J 0
(9350 3575);
DISPLAY 0.617021 (9350 3575);
PAINT BLUE (9350 3575);
FORCEPROP 2 LAST SEC 1
J 0
(9250 5100);
DISPLAY 0.680851 (9250 5100);
PAINT MONO (9250 5100);
DISPLAY INVISIBLE (9250 5100);
FORCEPROP 2 LAST SEC_TYPE SM
J 0
(9250 5100);
DISPLAY 1.021277 (9250 5100);
PAINT ORANGE (9250 5100);
DISPLAY INVISIBLE (9250 5100);
FORCEPROP 1 LAST PACK_TYPE SM
J 0
(9250 5100);
PAINT SKYBLUE (9250 5100);
DISPLAY INVISIBLE (9250 5100);
FORCEPROP 1 LAST PATH I116
J 0
(9700 5000);
PAINT GREEN (9700 5000);
DISPLAY INVISIBLE (9700 5000);
FORCEPROP 2 LAST CDS_LOCATION EU7A3
J 0
(9250 5050);
DISPLAY 0.617021 (9250 5050);
PAINT AQUA (9250 5050);
DISPLAY INVISIBLE (9250 5050);
FORCEPROP 2 LAST CDS_LIB mstr_discrete
J 0
(9700 4250);
PAINT ORANGE (9700 4250);
DISPLAY INVISIBLE (9700 4250);
FORCEADD IR354XX..1
(9725 2500);
FORCEPROP 1 LAST PART_NUMBER H73684-001
J 0
(9350 1800);
DISPLAY 0.617021 (9350 1800);
PAINT BLUE (9350 1800);
FORCEPROP 2 LASTPIN (10225 2850) $PN 37
J 0
(10235 2860);
DISPLAY 0.617021 (10235 2860);
PAINT ORANGE (10235 2860);
FORCEPROP 2 LASTPIN (9225 2300) $PN 39
J 2
(9215 2310);
DISPLAY 0.617021 (9215 2310);
PAINT ORANGE (9215 2310);
FORCEPROP 2 LASTPIN (9225 2400) $PN 34
J 2
(9215 2410);
DISPLAY 0.617021 (9215 2410);
PAINT ORANGE (9215 2410);
FORCEPROP 2 LASTPIN (9225 2150) $PN 32
J 2
(9215 2160);
DISPLAY 0.617021 (9215 2160);
PAINT ORANGE (9215 2160);
FORCEPROP 2 LASTPIN (9225 2500) $PN 6
J 2
(9215 2510);
DISPLAY 0.617021 (9215 2510);
PAINT ORANGE (9215 2510);
FORCEPROP 2 LASTPIN (9225 2200) $PN 33
J 2
(9215 2210);
DISPLAY 0.617021 (9215 2210);
PAINT ORANGE (9215 2210);
FORCEPROP 2 LASTPIN (9225 2550) $PN 41
J 2
(9215 2560);
DISPLAY 0.617021 (9215 2560);
PAINT ORANGE (9215 2560);
FORCEPROP 2 LASTPIN (9225 2650) $PN 1
J 2
(9215 2660);
DISPLAY 0.617021 (9215 2660);
PAINT ORANGE (9215 2660);
FORCEPROP 2 LASTPIN (9225 2750) $PN 35
J 2
(9215 2760);
DISPLAY 0.617021 (9215 2760);
PAINT ORANGE (9215 2760);
FORCEPROP 2 LASTPIN (9225 2850) $PN 4
J 2
(9215 2860);
DISPLAY 0.617021 (9215 2860);
PAINT ORANGE (9215 2860);
FORCEPROP 2 LASTPIN (9225 2950) $PN 25
J 2
(9215 2960);
DISPLAY 0.617021 (9215 2960);
PAINT ORANGE (9215 2960);
FORCEPROP 2 LASTPIN (9225 3000) $PN 30
J 2
(9215 3010);
DISPLAY 0.617021 (9215 3010);
PAINT ORANGE (9215 3010);
FORCEPROP 2 LASTPIN (9225 3050) $PN 3
J 2
(9215 3060);
DISPLAY 0.617021 (9215 3060);
PAINT ORANGE (9215 3060);
FORCEPROP 1 LAST LOCATION EU7A2
J 0
(9275 3300);
DISPLAY 0.617021 (9275 3300);
PAINT AQUA (9275 3300);
FORCEPROP 1 LAST MATERIAL IC
J 0
(9275 3250);
DISPLAY 0.617021 (9275 3250);
PAINT SKYBLUE (9275 3250);
FORCEPROP 2 LAST NO_XNET_CONNECTION 1
J 0
(9275 3350);
PAINT MONO (9275 3350);
FORCEPROP 1 LAST VALUE IR35412
J 1
(9725 3125);
DISPLAY 0.617021 (9725 3125);
PAINT SKYBLUE (9725 3125);
FORCEPROP 2 LASTPIN (10225 2200) $PN 10
J 0
(10235 2210);
DISPLAY 0.617021 (10235 2210);
PAINT ORANGE (10235 2210);
FORCEPROP 2 LASTPIN (10225 2050) $PN 40
J 0
(10235 2060);
DISPLAY 0.617021 (10235 2060);
PAINT ORANGE (10235 2060);
FORCEPROP 2 LASTPIN (10225 2000) $PN 7
J 0
(10235 2010);
DISPLAY 0.617021 (10235 2010);
PAINT ORANGE (10235 2010);
FORCEPROP 2 LASTPIN (10225 1950) $PN 5
J 0
(10235 1960);
DISPLAY 0.617021 (10235 1960);
PAINT ORANGE (10235 1960);
FORCEPROP 2 LASTPIN (10225 2800) $PN 31
J 0
(10235 2810);
DISPLAY 0.617021 (10235 2810);
PAINT ORANGE (10235 2810);
FORCEPROP 2 LASTPIN (10225 2100) $PN 2
J 0
(10235 2110);
DISPLAY 0.617021 (10235 2110);
PAINT ORANGE (10235 2110);
FORCEPROP 2 LASTPIN (10225 3050) $PN 38
J 0
(10235 3060);
DISPLAY 0.617021 (10235 3060);
PAINT ORANGE (10235 3060);
FORCEPROP 2 LASTPIN (10225 2550) $PN 36
J 0
(10235 2560);
DISPLAY 0.617021 (10235 2560);
PAINT ORANGE (10235 2560);
FORCEPROP 2 LAST CDS_LIB mstr_discrete
J 0
(9725 2500);
PAINT ORANGE (9725 2500);
DISPLAY INVISIBLE (9725 2500);
FORCEPROP 1 LAST PACK_TYPE SM
J 0
(9275 3350);
PAINT SKYBLUE (9275 3350);
DISPLAY INVISIBLE (9275 3350);
FORCEPROP 2 LAST SEC_TYPE SM
J 0
(9275 3350);
DISPLAY 1.021277 (9275 3350);
PAINT ORANGE (9275 3350);
DISPLAY INVISIBLE (9275 3350);
FORCEPROP 2 LAST SEC 1
J 0
(9275 3350);
DISPLAY 0.680851 (9275 3350);
PAINT MONO (9275 3350);
DISPLAY INVISIBLE (9275 3350);
FORCEPROP 2 LAST CDS_LOCATION EU7A2
J 0
(9275 3300);
DISPLAY 0.617021 (9275 3300);
PAINT AQUA (9275 3300);
DISPLAY INVISIBLE (9275 3300);
FORCEPROP 1 LAST PATH I117
J 0
(9725 3250);
PAINT GREEN (9725 3250);
DISPLAY INVISIBLE (9725 3250);
FORCEADD RES..2
(11975 4425);
FORCEPROP 1 LAST PART_NUMBER G21796-187
J 0
(12015 4300);
DISPLAY 0.617021 (12015 4300);
PAINT BLUE (12015 4300);
FORCEPROP 1 LAST WATTAGE 1/16W
J 0
(12015 4400);
DISPLAY 0.617021 (12015 4400);
PAINT SKYBLUE (12015 4400);
FORCEPROP 1 LAST PACK_TYPE 0402
J 0
(12015 4250);
DISPLAY 0.617021 (12015 4250);
PAINT SKYBLUE (12015 4250);
FORCEPROP 1 LAST TOLERANCE 1%
J 0
(12020 4450);
DISPLAY 0.617021 (12020 4450);
PAINT SKYBLUE (12020 4450);
FORCEPROP 1 LAST VALUE 68.1K
J 0
(12020 4500);
DISPLAY 0.617021 (12020 4500);
PAINT SKYBLUE (12020 4500);
FORCEPROP 1 LAST LOCATION R3L15
J 0
(12020 4550);
DISPLAY 0.617021 (12020 4550);
PAINT AQUA (12020 4550);
FORCEPROP 1 LAST MATERIAL EMPTY
J 0
(12015 4350);
DISPLAY 0.617021 (12015 4350);
PAINT RED (12015 4350);
FORCEPROP 2 LAST $SEC 1
J 0
(12025 4650);
PAINT MONO (12025 4650);
DISPLAY INVISIBLE (12025 4650);
FORCEPROP 2 LAST CDS_SEC 1
J 0
(12025 4650);
PAINT MONO (12025 4650);
DISPLAY INVISIBLE (12025 4650);
FORCEPROP 1 LAST PATH I118
J 0
(12025 4600);
DISPLAY 0.978723 (12025 4600);
PAINT WHITE (12025 4600);
DISPLAY INVISIBLE (12025 4600);
FORCEPROP 1 LASTPIN (11975 4525) $PN 1
J 0
(11980 4487);
DISPLAY 0.787234 (11980 4487);
PAINT ORANGE (11980 4487);
DISPLAY INVISIBLE (11980 4487);
FORCEPROP 2 LAST CDS_LIB mstr_discrete
J 0
(11975 4425);
PAINT ORANGE (11975 4425);
DISPLAY INVISIBLE (11975 4425);
FORCEPROP 1 LASTPIN (11975 4325) $PN 2
J 0
(11980 4335);
DISPLAY 0.787234 (11980 4335);
PAINT ORANGE (11980 4335);
DISPLAY INVISIBLE (11980 4335);
FORCEADD GND..1
(11975 4175);
FORCEPROP 3 LASTPIN (11975 4225) SIG_NAME GND\g
J 0
(11985 4235);
DISPLAY 0.659574 (11985 4235);
PAINT MONO (11985 4235);
DISPLAY INVISIBLE (11985 4235);
FORCEPROP 1 LAST PATH I119
J 0
(12050 4175);
DISPLAY 0.872340 (12050 4175);
PAINT AQUA (12050 4175);
DISPLAY INVISIBLE (12050 4175);
FORCEPROP 1 LAST SIZE 1B
J 0
(12050 4125);
DISPLAY 1.723404 (12050 4125);
PAINT GREEN (12050 4125);
DISPLAY INVISIBLE (12050 4125);
FORCEPROP 2 LAST CDS_LIB mstr_symbols
J 0
(11975 4175);
PAINT ORANGE (11975 4175);
DISPLAY INVISIBLE (11975 4175);
FORCEPROP 1 LAST VOLTAGE 0
J 0
(11975 4175);
PAINT SKYBLUE (11975 4175);
DISPLAY INVISIBLE (11975 4175);
FORCEPROP 2 LAST ROOM PVSA_CPU1_PWR_VR
J 0
(11425 4250);
DISPLAY 1.936170 (11425 4250);
PAINT ORANGE (11425 4250);
DISPLAY INVISIBLE (11425 4250);
FORCEPROP 2 LAST BOM_COST PROC_VRD_VCCIN_CPU0
J 0
(11600 4250);
DISPLAY 1.446809 (11600 4250);
PAINT MONO (11600 4250);
DISPLAY INVISIBLE (11600 4250);
FORCEPROP 1 LAST BODY_TYPE PLUMBING
J 0
(11930 4132);
DISPLAY 0.340426 (11930 4132);
PAINT GREEN (11930 4132);
DISPLAY INVISIBLE (11930 4132);
FORCEPROP 1 LAST HDL_POWER GND
J 0
(11975 4325);
DISPLAY 1.723404 (11975 4325);
PAINT GREEN (11975 4325);
DISPLAY INVISIBLE (11975 4325);
FORCEADD RES..2
(12000 2675);
FORCEPROP 1 LAST WATTAGE 1/16W
J 0
(12040 2650);
DISPLAY 0.617021 (12040 2650);
PAINT SKYBLUE (12040 2650);
FORCEPROP 1 LAST TOLERANCE 1%
J 0
(12045 2700);
DISPLAY 0.617021 (12045 2700);
PAINT SKYBLUE (12045 2700);
FORCEPROP 1 LAST VALUE 68.1K
J 0
(12045 2750);
DISPLAY 0.617021 (12045 2750);
PAINT SKYBLUE (12045 2750);
FORCEPROP 1 LAST LOCATION R3L14
J 0
(12045 2800);
DISPLAY 0.617021 (12045 2800);
PAINT AQUA (12045 2800);
FORCEPROP 1 LAST MATERIAL EMPTY
J 0
(12040 2600);
DISPLAY 0.617021 (12040 2600);
PAINT RED (12040 2600);
FORCEPROP 1 LAST PART_NUMBER G21796-187
J 0
(12040 2550);
DISPLAY 0.617021 (12040 2550);
PAINT BLUE (12040 2550);
FORCEPROP 1 LAST PACK_TYPE 0402
J 0
(12040 2500);
DISPLAY 0.617021 (12040 2500);
PAINT SKYBLUE (12040 2500);
FORCEPROP 1 LAST PATH I120
J 0
(12050 2850);
DISPLAY 0.978723 (12050 2850);
PAINT WHITE (12050 2850);
DISPLAY INVISIBLE (12050 2850);
FORCEPROP 2 LAST $SEC 1
J 0
(12050 2900);
PAINT MONO (12050 2900);
DISPLAY INVISIBLE (12050 2900);
FORCEPROP 2 LAST CDS_SEC 1
J 0
(12050 2900);
PAINT MONO (12050 2900);
DISPLAY INVISIBLE (12050 2900);
FORCEPROP 1 LASTPIN (12000 2775) $PN 1
J 0
(12005 2737);
DISPLAY 0.787234 (12005 2737);
PAINT ORANGE (12005 2737);
DISPLAY INVISIBLE (12005 2737);
FORCEPROP 2 LAST CDS_LIB mstr_discrete
J 0
(12000 2675);
PAINT ORANGE (12000 2675);
DISPLAY INVISIBLE (12000 2675);
FORCEPROP 1 LASTPIN (12000 2575) $PN 2
J 0
(12005 2585);
DISPLAY 0.787234 (12005 2585);
PAINT ORANGE (12005 2585);
DISPLAY INVISIBLE (12005 2585);
FORCEADD GND..1
(12000 2425);
FORCEPROP 3 LASTPIN (12000 2475) SIG_NAME GND\g
J 0
(12010 2485);
DISPLAY 0.659574 (12010 2485);
PAINT MONO (12010 2485);
DISPLAY INVISIBLE (12010 2485);
FORCEPROP 1 LAST SIZE 1B
J 0
(12075 2375);
DISPLAY 1.723404 (12075 2375);
PAINT GREEN (12075 2375);
DISPLAY INVISIBLE (12075 2375);
FORCEPROP 1 LAST PATH I121
J 0
(12075 2425);
DISPLAY 0.872340 (12075 2425);
PAINT AQUA (12075 2425);
DISPLAY INVISIBLE (12075 2425);
FORCEPROP 2 LAST CDS_LIB mstr_symbols
J 0
(12000 2425);
PAINT ORANGE (12000 2425);
DISPLAY INVISIBLE (12000 2425);
FORCEPROP 1 LAST VOLTAGE 0
J 0
(12000 2425);
PAINT SKYBLUE (12000 2425);
DISPLAY INVISIBLE (12000 2425);
FORCEPROP 2 LAST ROOM PVSA_CPU1_PWR_VR
J 0
(11450 2500);
DISPLAY 1.936170 (11450 2500);
PAINT ORANGE (11450 2500);
DISPLAY INVISIBLE (11450 2500);
FORCEPROP 2 LAST BOM_COST PROC_VRD_VCCIN_CPU0
J 0
(11625 2500);
DISPLAY 1.446809 (11625 2500);
PAINT MONO (11625 2500);
DISPLAY INVISIBLE (11625 2500);
FORCEPROP 1 LAST BODY_TYPE PLUMBING
J 0
(11955 2382);
DISPLAY 0.340426 (11955 2382);
PAINT GREEN (11955 2382);
DISPLAY INVISIBLE (11955 2382);
FORCEPROP 1 LAST HDL_POWER GND
J 0
(12000 2575);
DISPLAY 1.723404 (12000 2575);
PAINT GREEN (12000 2575);
DISPLAY INVISIBLE (12000 2575);
FORCEADD P5V_STBY..1
(8375 5125);
FORCEPROP 3 LASTPIN (8375 5075) SIG_NAME P5V_STBY\g
J 0
(8385 5085);
DISPLAY 0.659574 (8385 5085);
PAINT MONO (8385 5085);
DISPLAY INVISIBLE (8385 5085);
FORCEPROP 1 LAST PATH I122
J 0
(8420 5127);
DISPLAY 0.340426 (8420 5127);
PAINT GREEN (8420 5127);
DISPLAY INVISIBLE (8420 5127);
FORCEPROP 2 LAST CDS_LIB mstr_symbols
J 0
(8375 5125);
PAINT ORANGE (8375 5125);
DISPLAY INVISIBLE (8375 5125);
FORCEPROP 1 LAST SIZE 1B
J 0
(8420 5147);
DISPLAY 0.340426 (8420 5147);
PAINT GREEN (8420 5147);
DISPLAY INVISIBLE (8420 5147);
FORCEPROP 1 LAST VOLTAGE 5.0V
J 0
(8330 5082);
DISPLAY 0.340426 (8330 5082);
PAINT SKYBLUE (8330 5082);
DISPLAY INVISIBLE (8330 5082);
FORCEPROP 1 LAST BODY_TYPE PLUMBING
J 0
(8330 5082);
DISPLAY 0.340426 (8330 5082);
PAINT GREEN (8330 5082);
DISPLAY INVISIBLE (8330 5082);
FORCEPROP 1 LAST HDL_POWER P5V_STBY
J 0
(8075 5000);
DISPLAY 0.872340 (8075 5000);
PAINT ORANGE (8075 5000);
DISPLAY INVISIBLE (8075 5000);
FORCEADD CAP_A..1
(8975 2000);
FORCEPROP 0 LAST STATUS NOPOP
J 0
(8750 1850);
DISPLAY 1.021277 (8750 1850);
PAINT ORANGE (8750 1850);
FORCEPROP 1 LAST PART_NUMBER A36096-030
J 0
(9025 1850);
DISPLAY 0.617021 (9025 1850);
PAINT BLUE (9025 1850);
FORCEPROP 1 LAST LOCATION CT67
J 0
(8825 2000);
DISPLAY 0.617021 (8825 2000);
PAINT AQUA (8825 2000);
FORCEPROP 1 LAST VALUE 0.1UF
J 0
(9025 2050);
DISPLAY 0.617021 (9025 2050);
PAINT SKYBLUE (9025 2050);
FORCEPROP 1 LAST VOLTAGE 16V
J 0
(9025 2000);
DISPLAY 0.617021 (9025 2000);
PAINT SKYBLUE (9025 2000);
FORCEPROP 1 LAST TOLERANCE 10%
J 0
(9025 1950);
DISPLAY 0.617021 (9025 1950);
PAINT SKYBLUE (9025 1950);
FORCEPROP 1 LAST MATERIAL X7R
J 0
(9025 1900);
DISPLAY 0.617021 (9025 1900);
PAINT SKYBLUE (9025 1900);
FORCEPROP 1 LAST PACK_TYPE 0402V
J 0
(9025 1800);
DISPLAY 0.617021 (9025 1800);
PAINT SKYBLUE (9025 1800);
FORCEPROP 2 LAST CDS_LIB dev_discrete
J 0
(8975 2000);
PAINT MONO (8975 2000);
DISPLAY INVISIBLE (8975 2000);
FORCEPROP 1 LAST PATH I124
J 0
(9025 2150);
DISPLAY 0.978723 (9025 2150);
PAINT WHITE (9025 2150);
DISPLAY INVISIBLE (9025 2150);
FORCEPROP 2 LAST ROOM PVCCIN_CPU0_PWR_VR
J 0
(9025 2150);
DISPLAY 1.361702 (9025 2150);
PAINT ORANGE (9025 2150);
DISPLAY INVISIBLE (9025 2150);
FORCEPROP 1 LASTPIN (8975 2100) $PN 1
J 0
(8985 2080);
DISPLAY 0.787234 (8985 2080);
PAINT ORANGE (8985 2080);
DISPLAY INVISIBLE (8985 2080);
FORCEPROP 1 LASTPIN (8975 1900) $PN 2
J 0
(8985 1880);
DISPLAY 0.787234 (8985 1880);
PAINT ORANGE (8985 1880);
DISPLAY INVISIBLE (8985 1880);
FORCEADD GND..1
(8975 1750);
FORCEPROP 3 LASTPIN (8975 1800) SIG_NAME GND\g
J 0
(8985 1810);
DISPLAY 0.659574 (8985 1810);
PAINT MONO (8985 1810);
DISPLAY INVISIBLE (8985 1810);
FORCEPROP 2 LAST CDS_LIB mstr_symbols
J 0
(8975 1750);
PAINT MONO (8975 1750);
DISPLAY INVISIBLE (8975 1750);
FORCEPROP 1 LAST PATH I125
J 0
(9050 1750);
DISPLAY 0.872340 (9050 1750);
PAINT AQUA (9050 1750);
DISPLAY INVISIBLE (9050 1750);
FORCEPROP 1 LAST VOLTAGE 0
J 0
(8975 1750);
PAINT SKYBLUE (8975 1750);
DISPLAY INVISIBLE (8975 1750);
FORCEPROP 1 LAST SIZE 1B
J 0
(9050 1700);
DISPLAY 1.723404 (9050 1700);
PAINT GREEN (9050 1700);
DISPLAY INVISIBLE (9050 1700);
FORCEPROP 2 LAST BOM_COST PROC_VRD_VCCIN_CPU0
J 0
(8600 1825);
DISPLAY 1.446809 (8600 1825);
PAINT MONO (8600 1825);
DISPLAY INVISIBLE (8600 1825);
FORCEPROP 2 LAST ROOM PVCCIN_CPU0_PWR_VR
J 0
(8425 1825);
DISPLAY 1.936170 (8425 1825);
PAINT ORANGE (8425 1825);
DISPLAY INVISIBLE (8425 1825);
FORCEPROP 1 LAST BODY_TYPE PLUMBING
J 0
(8930 1707);
DISPLAY 0.340426 (8930 1707);
PAINT GREEN (8930 1707);
DISPLAY INVISIBLE (8930 1707);
FORCEPROP 1 LAST HDL_POWER GND
J 0
(8975 1900);
DISPLAY 1.723404 (8975 1900);
PAINT GREEN (8975 1900);
DISPLAY INVISIBLE (8975 1900);
FORCEADD GND..1
(8975 3475);
FORCEPROP 3 LASTPIN (8975 3525) SIG_NAME GND\g
J 0
(8985 3535);
DISPLAY 0.659574 (8985 3535);
PAINT MONO (8985 3535);
DISPLAY INVISIBLE (8985 3535);
FORCEPROP 2 LAST CDS_LIB mstr_symbols
J 0
(8975 3475);
PAINT MONO (8975 3475);
DISPLAY INVISIBLE (8975 3475);
FORCEPROP 1 LAST PATH I126
J 0
(9050 3475);
DISPLAY 0.872340 (9050 3475);
PAINT AQUA (9050 3475);
DISPLAY INVISIBLE (9050 3475);
FORCEPROP 2 LAST ROOM PVCCIN_CPU0_PWR_VR
J 0
(8425 3550);
DISPLAY 1.936170 (8425 3550);
PAINT ORANGE (8425 3550);
DISPLAY INVISIBLE (8425 3550);
FORCEPROP 2 LAST BOM_COST PROC_VRD_VCCIN_CPU0
J 0
(8600 3550);
DISPLAY 1.446809 (8600 3550);
PAINT MONO (8600 3550);
DISPLAY INVISIBLE (8600 3550);
FORCEPROP 1 LAST SIZE 1B
J 0
(9050 3425);
DISPLAY 1.723404 (9050 3425);
PAINT GREEN (9050 3425);
DISPLAY INVISIBLE (9050 3425);
FORCEPROP 1 LAST VOLTAGE 0
J 0
(8975 3475);
PAINT SKYBLUE (8975 3475);
DISPLAY INVISIBLE (8975 3475);
FORCEPROP 1 LAST BODY_TYPE PLUMBING
J 0
(8930 3432);
DISPLAY 0.340426 (8930 3432);
PAINT GREEN (8930 3432);
DISPLAY INVISIBLE (8930 3432);
FORCEPROP 1 LAST HDL_POWER GND
J 0
(8975 3625);
DISPLAY 1.723404 (8975 3625);
PAINT GREEN (8975 3625);
DISPLAY INVISIBLE (8975 3625);
FORCEADD CAP_A..1
(8975 3750);
FORCEPROP 0 LAST STATUS NOPOP
J 0
(8725 3575);
DISPLAY 1.021277 (8725 3575);
PAINT ORANGE (8725 3575);
FORCEPROP 1 LAST TOLERANCE 10%
J 0
(9025 3700);
DISPLAY 0.617021 (9025 3700);
PAINT SKYBLUE (9025 3700);
FORCEPROP 1 LAST MATERIAL X7R
J 0
(9025 3650);
DISPLAY 0.617021 (9025 3650);
PAINT SKYBLUE (9025 3650);
FORCEPROP 1 LAST PACK_TYPE 0402V
J 0
(9025 3550);
DISPLAY 0.617021 (9025 3550);
PAINT SKYBLUE (9025 3550);
FORCEPROP 1 LAST PART_NUMBER A36096-030
J 0
(9025 3600);
DISPLAY 0.617021 (9025 3600);
PAINT BLUE (9025 3600);
FORCEPROP 1 LAST VOLTAGE 16V
J 0
(9025 3750);
DISPLAY 0.617021 (9025 3750);
PAINT SKYBLUE (9025 3750);
FORCEPROP 1 LAST VALUE 0.1UF
J 0
(9025 3800);
DISPLAY 0.617021 (9025 3800);
PAINT SKYBLUE (9025 3800);
FORCEPROP 1 LAST LOCATION CT66
J 0
(8825 3750);
DISPLAY 0.617021 (8825 3750);
PAINT AQUA (8825 3750);
FORCEPROP 2 LAST CDS_LIB dev_discrete
J 0
(8975 3750);
PAINT MONO (8975 3750);
DISPLAY INVISIBLE (8975 3750);
FORCEPROP 1 LAST PATH I127
J 0
(9025 3900);
DISPLAY 0.978723 (9025 3900);
PAINT WHITE (9025 3900);
DISPLAY INVISIBLE (9025 3900);
FORCEPROP 2 LAST ROOM PVCCIN_CPU0_PWR_VR
J 0
(9025 3900);
DISPLAY 1.361702 (9025 3900);
PAINT ORANGE (9025 3900);
DISPLAY INVISIBLE (9025 3900);
FORCEPROP 1 LASTPIN (8975 3850) $PN 1
J 0
(8985 3830);
DISPLAY 0.787234 (8985 3830);
PAINT ORANGE (8985 3830);
DISPLAY INVISIBLE (8985 3830);
FORCEPROP 1 LASTPIN (8975 3650) $PN 2
J 0
(8985 3630);
DISPLAY 0.787234 (8985 3630);
PAINT ORANGE (8985 3630);
DISPLAY INVISIBLE (8985 3630);
FORCEADD GND..1
(10775 4050);
FORCEPROP 3 LASTPIN (10775 4100) SIG_NAME GND\g
J 0
(10785 4110);
DISPLAY 0.659574 (10785 4110);
PAINT MONO (10785 4110);
DISPLAY INVISIBLE (10785 4110);
FORCEPROP 2 LAST ROOM VDDQ_KLM_PWR_VR
J 0
(10200 4125);
DISPLAY 1.361702 (10200 4125);
PAINT ORANGE (10200 4125);
DISPLAY INVISIBLE (10200 4125);
FORCEPROP 1 LAST VOLTAGE 0
J 0
(10775 4050);
PAINT SKYBLUE (10775 4050);
DISPLAY INVISIBLE (10775 4050);
FORCEPROP 1 LAST SIZE 1B
J 0
(10850 4000);
DISPLAY 1.170213 (10850 4000);
PAINT AQUA (10850 4000);
DISPLAY INVISIBLE (10850 4000);
FORCEPROP 1 LAST PATH I130
J 0
(10850 4050);
DISPLAY 0.872340 (10850 4050);
PAINT AQUA (10850 4050);
DISPLAY INVISIBLE (10850 4050);
FORCEPROP 2 LAST CDS_LIB mstr_symbols
J 0
(10775 4050);
PAINT MONO (10775 4050);
DISPLAY INVISIBLE (10775 4050);
FORCEPROP 1 LAST BODY_TYPE PLUMBING
J 0
(10730 4007);
DISPLAY 0.340426 (10730 4007);
PAINT GREEN (10730 4007);
DISPLAY INVISIBLE (10730 4007);
FORCEPROP 1 LAST HDL_POWER GND
J 0
(10775 4200);
DISPLAY 1.170213 (10775 4200);
PAINT GREEN (10775 4200);
DISPLAY INVISIBLE (10775 4200);
FORCEADD SC2K2P50V3KX-GP..1
(10750 3850);
FORCEPROP 1 LAST LOCATION CT65
J 0
(10775 3880);
DISPLAY 0.617021 (10775 3880);
PAINT GREEN (10775 3880);
FORCEPROP 0 LAST STATUS NOPOP
J 0
(10775 3750);
DISPLAY 1.021277 (10775 3750);
PAINT ORANGE (10775 3750);
FORCEPROP 1 LAST VALUE SC2K2P50V3KX-GP
J 0
(10775 3800);
DISPLAY 0.617021 (10775 3800);
PAINT GREEN (10775 3800);
FORCEPROP 2 LAST CDS_LIB w_hdl
J 0
(10750 3850);
PAINT MONO (10750 3850);
DISPLAY INVISIBLE (10750 3850);
FORCEPROP 1 LAST CDS_LMAN_SYM_OUTLINE -50,25,50,-25
J 0
(10750 3850);
DISPLAY 0.468085 (10750 3850);
PAINT GREEN (10750 3850);
DISPLAY INVISIBLE (10750 3850);
FORCEPROP 1 LAST PATH I131
J 0
(10750 3850);
DISPLAY 0.617021 (10750 3850);
PAINT GREEN (10750 3850);
DISPLAY INVISIBLE (10750 3850);
FORCEPROP 1 LAST PACK_TYPE SMD-BCG6
J 0
(10750 3850);
DISPLAY 0.617021 (10750 3850);
PAINT GREEN (10750 3850);
DISPLAY INVISIBLE (10750 3850);
FORCEPROP 1 LAST PART_NUMBER 78.22224.2BL
J 0
(10750 3850);
DISPLAY 0.617021 (10750 3850);
PAINT GREEN (10750 3850);
DISPLAY INVISIBLE (10750 3850);
FORCEADD 3D01R5F-GP..1
R 4
(10750 3575);
FORCEPROP 1 LAST LOCATION RT43
J 0
(10625 3570);
DISPLAY 0.617021 (10625 3570);
PAINT GREEN (10625 3570);
FORCEPROP 0 LAST STATUS NOPOP
J 0
(10775 3475);
DISPLAY 1.021277 (10775 3475);
PAINT ORANGE (10775 3475);
FORCEPROP 1 LAST VALUE 3D01R5F-GP
J 0
(10525 3525);
DISPLAY 0.617021 (10525 3525);
PAINT GREEN (10525 3525);
FORCEPROP 1 LAST CDS_LMAN_SYM_OUTLINE -50,75,50,-75
R 2
J 0
(10750 3575);
DISPLAY 0.468085 (10750 3575);
PAINT GREEN (10750 3575);
DISPLAY INVISIBLE (10750 3575);
FORCEPROP 1 LAST PATH I132
R 2
J 0
(10750 3575);
DISPLAY 0.617021 (10750 3575);
PAINT GREEN (10750 3575);
DISPLAY INVISIBLE (10750 3575);
FORCEPROP 2 LAST CDS_LIB w_hdl
J 0
(10750 3575);
PAINT MONO (10750 3575);
DISPLAY INVISIBLE (10750 3575);
FORCEPROP 1 LAST PART_NUMBER 64.3R015.16L
R 2
J 0
(10750 3575);
DISPLAY 0.617021 (10750 3575);
PAINT GREEN (10750 3575);
DISPLAY INVISIBLE (10750 3575);
FORCEPROP 1 LAST PACK_TYPE SMD-RG5
R 2
J 0
(10750 3575);
DISPLAY 0.617021 (10750 3575);
PAINT GREEN (10750 3575);
DISPLAY INVISIBLE (10750 3575);
FORCEPROP 2 LASTPIN (10750 3700) SIG_NAME UN$236$3D01R5F-GP$I132$2
J 0
(10760 3710);
DISPLAY 0.659574 (10760 3710);
PAINT MONO (10760 3710);
DISPLAY INVISIBLE (10760 3710);
FORCEADD GND..1
(10750 3375);
FORCEPROP 3 LASTPIN (10750 3425) SIG_NAME GND\g
J 0
(10760 3435);
DISPLAY 0.659574 (10760 3435);
PAINT MONO (10760 3435);
DISPLAY INVISIBLE (10760 3435);
FORCEPROP 2 LAST CDS_LIB mstr_symbols
J 0
(10750 3375);
PAINT MONO (10750 3375);
DISPLAY INVISIBLE (10750 3375);
FORCEPROP 1 LAST PATH I133
J 0
(10825 3375);
DISPLAY 0.872340 (10825 3375);
PAINT AQUA (10825 3375);
DISPLAY INVISIBLE (10825 3375);
FORCEPROP 1 LAST SIZE 1B
J 0
(10825 3325);
DISPLAY 1.723404 (10825 3325);
PAINT GREEN (10825 3325);
DISPLAY INVISIBLE (10825 3325);
FORCEPROP 1 LAST VOLTAGE 0
J 0
(10750 3375);
PAINT SKYBLUE (10750 3375);
DISPLAY INVISIBLE (10750 3375);
FORCEPROP 2 LAST BOM_COST PROC_VRD_VCCIN_CPU0
J 0
(10375 3450);
DISPLAY 1.446809 (10375 3450);
PAINT MONO (10375 3450);
DISPLAY INVISIBLE (10375 3450);
FORCEPROP 2 LAST ROOM PVCCIN_CPU0_PWR_VR
J 0
(10200 3450);
DISPLAY 1.936170 (10200 3450);
PAINT ORANGE (10200 3450);
DISPLAY INVISIBLE (10200 3450);
FORCEPROP 1 LAST BODY_TYPE PLUMBING
J 0
(10705 3332);
DISPLAY 0.340426 (10705 3332);
PAINT GREEN (10705 3332);
DISPLAY INVISIBLE (10705 3332);
FORCEPROP 1 LAST HDL_POWER GND
J 0
(10750 3525);
DISPLAY 1.723404 (10750 3525);
PAINT GREEN (10750 3525);
DISPLAY INVISIBLE (10750 3525);
FORCEADD CAP..1
(10750 2575);
FORCEPROP 0 LAST STATUS NOPOP
J 0
(10775 2650);
DISPLAY 1.021277 (10775 2650);
PAINT ORANGE (10775 2650);
FORCEPROP 1 LAST PART_NUMBER A36096-046
J 0
(10800 2425);
DISPLAY 0.617021 (10800 2425);
PAINT BLUE (10800 2425);
FORCEPROP 1 LAST LOCATION CT69
J 0
(10600 2575);
DISPLAY 0.617021 (10600 2575);
PAINT AQUA (10600 2575);
FORCEPROP 1 LAST MATERIAL X7R
J 0
(10800 2475);
DISPLAY 0.617021 (10800 2475);
PAINT SKYBLUE (10800 2475);
FORCEPROP 1 LAST VOLTAGE 50V
J 0
(10800 2575);
DISPLAY 0.617021 (10800 2575);
PAINT SKYBLUE (10800 2575);
FORCEPROP 1 LAST TOLERANCE 10%
J 0
(10800 2525);
DISPLAY 0.617021 (10800 2525);
PAINT SKYBLUE (10800 2525);
FORCEPROP 1 LAST PACK_TYPE 0402LF
J 0
(10800 2375);
DISPLAY 0.617021 (10800 2375);
PAINT SKYBLUE (10800 2375);
FORCEPROP 1 LAST VALUE 1000PF
J 0
(10800 2625);
DISPLAY 0.617021 (10800 2625);
PAINT SKYBLUE (10800 2625);
FORCEPROP 2 LAST CDS_LIB mstr_discrete
J 0
(10750 2575);
PAINT MONO (10750 2575);
DISPLAY INVISIBLE (10750 2575);
FORCEPROP 1 LAST PATH I134
J 0
(10800 2725);
DISPLAY 0.978723 (10800 2725);
PAINT WHITE (10800 2725);
DISPLAY INVISIBLE (10800 2725);
FORCEPROP 0 LAST ROOM VDDQ_KLM_PWR_VR
J 0
(10800 2775);
DISPLAY 1.021277 (10800 2775);
PAINT ORANGE (10800 2775);
DISPLAY INVISIBLE (10800 2775);
FORCEPROP 1 LASTPIN (10750 2475) $PN 2
J 0
(10760 2455);
DISPLAY 0.787234 (10760 2455);
PAINT ORANGE (10760 2455);
DISPLAY INVISIBLE (10760 2455);
FORCEPROP 1 LASTPIN (10750 2675) $PN 1
J 0
(10760 2655);
DISPLAY 0.787234 (10760 2655);
PAINT ORANGE (10760 2655);
DISPLAY INVISIBLE (10760 2655);
FORCEADD GND..1
(10750 2400);
FORCEPROP 3 LASTPIN (10750 2450) SIG_NAME GND\g
J 0
(10760 2460);
DISPLAY 0.659574 (10760 2460);
PAINT MONO (10760 2460);
DISPLAY INVISIBLE (10760 2460);
FORCEPROP 2 LAST CDS_LIB mstr_symbols
J 0
(10750 2400);
PAINT MONO (10750 2400);
DISPLAY INVISIBLE (10750 2400);
FORCEPROP 1 LAST PATH I135
J 0
(10825 2400);
DISPLAY 0.872340 (10825 2400);
PAINT AQUA (10825 2400);
DISPLAY INVISIBLE (10825 2400);
FORCEPROP 1 LAST SIZE 1B
J 0
(10825 2350);
DISPLAY 1.170213 (10825 2350);
PAINT AQUA (10825 2350);
DISPLAY INVISIBLE (10825 2350);
FORCEPROP 1 LAST VOLTAGE 0
J 0
(10750 2400);
PAINT SKYBLUE (10750 2400);
DISPLAY INVISIBLE (10750 2400);
FORCEPROP 2 LAST ROOM VDDQ_KLM_PWR_VR
J 0
(10175 2475);
DISPLAY 1.361702 (10175 2475);
PAINT ORANGE (10175 2475);
DISPLAY INVISIBLE (10175 2475);
FORCEPROP 1 LAST BODY_TYPE PLUMBING
J 0
(10705 2357);
DISPLAY 0.340426 (10705 2357);
PAINT GREEN (10705 2357);
DISPLAY INVISIBLE (10705 2357);
FORCEPROP 1 LAST HDL_POWER GND
J 0
(10750 2550);
DISPLAY 1.170213 (10750 2550);
PAINT GREEN (10750 2550);
DISPLAY INVISIBLE (10750 2550);
FORCEADD CAP..1
(10775 4275);
FORCEPROP 1 LAST LOCATION CT64
J 0
(10825 4350);
DISPLAY 0.617021 (10825 4350);
PAINT AQUA (10825 4350);
FORCEPROP 1 LAST VOLTAGE 50V
J 0
(10825 4275);
DISPLAY 0.617021 (10825 4275);
PAINT SKYBLUE (10825 4275);
FORCEPROP 1 LAST VALUE 1000PF
J 0
(10825 4325);
DISPLAY 0.617021 (10825 4325);
PAINT SKYBLUE (10825 4325);
FORCEPROP 0 LAST STATUS NOPOP
J 0
(10925 4250);
DISPLAY 1.021277 (10925 4250);
PAINT ORANGE (10925 4250);
FORCEPROP 1 LAST TOLERANCE 10%
J 0
(10825 4225);
DISPLAY 0.617021 (10825 4225);
PAINT SKYBLUE (10825 4225);
FORCEPROP 1 LAST PART_NUMBER A36096-046
J 0
(10825 4125);
DISPLAY 0.617021 (10825 4125);
PAINT BLUE (10825 4125);
FORCEPROP 1 LAST MATERIAL X7R
J 0
(10825 4175);
DISPLAY 0.617021 (10825 4175);
PAINT SKYBLUE (10825 4175);
FORCEPROP 1 LAST PACK_TYPE 0402LF
J 0
(10825 4075);
DISPLAY 0.617021 (10825 4075);
PAINT SKYBLUE (10825 4075);
FORCEPROP 1 LAST PATH I136
J 0
(10825 4425);
DISPLAY 0.978723 (10825 4425);
PAINT WHITE (10825 4425);
DISPLAY INVISIBLE (10825 4425);
FORCEPROP 0 LAST ROOM VDDQ_KLM_PWR_VR
J 0
(10825 4475);
DISPLAY 1.021277 (10825 4475);
PAINT ORANGE (10825 4475);
DISPLAY INVISIBLE (10825 4475);
FORCEPROP 2 LAST CDS_LIB mstr_discrete
J 0
(10775 4275);
PAINT MONO (10775 4275);
DISPLAY INVISIBLE (10775 4275);
FORCEPROP 1 LASTPIN (10775 4175) $PN 2
J 0
(10785 4155);
DISPLAY 0.787234 (10785 4155);
PAINT ORANGE (10785 4155);
DISPLAY INVISIBLE (10785 4155);
FORCEPROP 1 LASTPIN (10775 4375) $PN 1
J 0
(10785 4355);
DISPLAY 0.787234 (10785 4355);
PAINT ORANGE (10785 4355);
DISPLAY INVISIBLE (10785 4355);
FORCEADD 3D01R5F-GP..1
R 4
(10800 1850);
FORCEPROP 0 LAST STATUS NOPOP
J 0
(10825 1850);
DISPLAY 1.021277 (10825 1850);
PAINT ORANGE (10825 1850);
FORCEPROP 1 LAST VALUE 3D01R5F-GP
J 0
(10600 1775);
DISPLAY 0.617021 (10600 1775);
PAINT GREEN (10600 1775);
FORCEPROP 1 LAST LOCATION RT45
J 0
(10675 1845);
DISPLAY 0.617021 (10675 1845);
PAINT GREEN (10675 1845);
FORCEPROP 2 LASTPIN (10800 1975) SIG_NAME UN$236$3D01R5F-GP$I137$2
J 0
(10810 1985);
DISPLAY 0.659574 (10810 1985);
PAINT MONO (10810 1985);
DISPLAY INVISIBLE (10810 1985);
FORCEPROP 1 LAST PACK_TYPE SMD-RG5
R 2
J 0
(10800 1850);
DISPLAY 0.617021 (10800 1850);
PAINT GREEN (10800 1850);
DISPLAY INVISIBLE (10800 1850);
FORCEPROP 1 LAST PART_NUMBER 64.3R015.16L
R 2
J 0
(10800 1850);
DISPLAY 0.617021 (10800 1850);
PAINT GREEN (10800 1850);
DISPLAY INVISIBLE (10800 1850);
FORCEPROP 2 LAST CDS_LIB w_hdl
J 0
(10800 1850);
PAINT MONO (10800 1850);
DISPLAY INVISIBLE (10800 1850);
FORCEPROP 1 LAST PATH I137
R 2
J 0
(10800 1850);
DISPLAY 0.617021 (10800 1850);
PAINT GREEN (10800 1850);
DISPLAY INVISIBLE (10800 1850);
FORCEPROP 1 LAST CDS_LMAN_SYM_OUTLINE -50,75,50,-75
R 2
J 0
(10800 1850);
DISPLAY 0.468085 (10800 1850);
PAINT GREEN (10800 1850);
DISPLAY INVISIBLE (10800 1850);
FORCEADD GND..1
(10800 1650);
FORCEPROP 3 LASTPIN (10800 1700) SIG_NAME GND\g
J 0
(10810 1710);
DISPLAY 0.659574 (10810 1710);
PAINT MONO (10810 1710);
DISPLAY INVISIBLE (10810 1710);
FORCEPROP 2 LAST CDS_LIB mstr_symbols
J 0
(10800 1650);
PAINT MONO (10800 1650);
DISPLAY INVISIBLE (10800 1650);
FORCEPROP 1 LAST PATH I139
J 0
(10875 1650);
DISPLAY 0.872340 (10875 1650);
PAINT AQUA (10875 1650);
DISPLAY INVISIBLE (10875 1650);
FORCEPROP 1 LAST SIZE 1B
J 0
(10875 1600);
DISPLAY 1.723404 (10875 1600);
PAINT GREEN (10875 1600);
DISPLAY INVISIBLE (10875 1600);
FORCEPROP 1 LAST VOLTAGE 0
J 0
(10800 1650);
PAINT SKYBLUE (10800 1650);
DISPLAY INVISIBLE (10800 1650);
FORCEPROP 2 LAST BOM_COST PROC_VRD_VCCIN_CPU0
J 0
(10425 1725);
DISPLAY 1.446809 (10425 1725);
PAINT MONO (10425 1725);
DISPLAY INVISIBLE (10425 1725);
FORCEPROP 2 LAST ROOM PVCCIN_CPU0_PWR_VR
J 0
(10250 1725);
DISPLAY 1.936170 (10250 1725);
PAINT ORANGE (10250 1725);
DISPLAY INVISIBLE (10250 1725);
FORCEPROP 1 LAST BODY_TYPE PLUMBING
J 0
(10755 1607);
DISPLAY 0.340426 (10755 1607);
PAINT GREEN (10755 1607);
DISPLAY INVISIBLE (10755 1607);
FORCEPROP 1 LAST HDL_POWER GND
J 0
(10800 1800);
DISPLAY 1.723404 (10800 1800);
PAINT GREEN (10800 1800);
DISPLAY INVISIBLE (10800 1800);
FORCEADD RES..1
(7175 5025);
FORCEPROP 1 LASTPIN (7275 5025) $PN 2
J 0
(7237 5037);
DISPLAY 0.617021 (7237 5037);
PAINT WHITE (7237 5037);
FORCEPROP 1 LAST MATERIAL CHIP
J 0
(7250 4850);
DISPLAY 0.617021 (7250 4850);
PAINT SKYBLUE (7250 4850);
FORCEPROP 1 LAST PACK_TYPE 0402
J 0
(7225 4900);
DISPLAY 0.617021 (7225 4900);
PAINT SKYBLUE (7225 4900);
FORCEPROP 1 LAST WATTAGE 1/16W
J 2
(7200 4850);
DISPLAY 0.617021 (7200 4850);
PAINT SKYBLUE (7200 4850);
FORCEPROP 1 LAST TOLERANCE 1%
J 0
(7125 4900);
DISPLAY 0.617021 (7125 4900);
PAINT SKYBLUE (7125 4900);
FORCEPROP 1 LAST PART_NUMBER G21796-090
J 0
(7050 4950);
DISPLAY 0.617021 (7050 4950);
PAINT BLUE (7050 4950);
FORCEPROP 1 LAST LOCATION R3L1
J 0
(7125 5075);
DISPLAY 0.617021 (7125 5075);
PAINT AQUA (7125 5075);
FORCEPROP 1 LASTPIN (7075 5025) $PN 1
J 0
(7087 5037);
DISPLAY 0.617021 (7087 5037);
PAINT WHITE (7087 5037);
FORCEPROP 1 LAST VALUE 1.0
J 2
(7075 4900);
DISPLAY 0.617021 (7075 4900);
PAINT SKYBLUE (7075 4900);
FORCEPROP 2 LAST CDS_LIB mstr_discrete
J 0
(7175 5025);
DISPLAY 1.617021 (7175 5025);
PAINT ORANGE (7175 5025);
DISPLAY INVISIBLE (7175 5025);
FORCEPROP 2 LAST ROOM PVNN_PCH_STBY
J 0
(7125 5125);
DISPLAY 2.212766 (7125 5125);
PAINT WHITE (7125 5125);
DISPLAY INVISIBLE (7125 5125);
FORCEPROP 1 LAST PATH I14
J 0
(7125 5175);
DISPLAY 0.978723 (7125 5175);
PAINT WHITE (7125 5175);
DISPLAY INVISIBLE (7125 5175);
FORCEPROP 2 LAST SEC 1
J 0
(7125 5225);
DISPLAY 1.106383 (7125 5225);
PAINT MONO (7125 5225);
DISPLAY INVISIBLE (7125 5225);
FORCEPROP 2 LAST SEC_TYPE 0402
J 0
(7125 5225);
DISPLAY 1.659574 (7125 5225);
PAINT ORANGE (7125 5225);
DISPLAY INVISIBLE (7125 5225);
FORCEPROP 2 LAST CDS_LOCATION R3L1
J 0
(7125 5075);
DISPLAY 0.617021 (7125 5075);
PAINT AQUA (7125 5075);
DISPLAY INVISIBLE (7125 5075);
FORCEADD SC2K2P50V3KX-GP..1
(10800 2100);
FORCEPROP 1 LAST LOCATION CT68
J 0
(10825 2130);
DISPLAY 0.617021 (10825 2130);
PAINT GREEN (10825 2130);
FORCEPROP 1 LAST VALUE SC2K2P50V3KX-GP
J 0
(10825 2050);
DISPLAY 0.617021 (10825 2050);
PAINT GREEN (10825 2050);
FORCEPROP 0 LAST STATUS NOPOP
J 0
(10825 2000);
DISPLAY 1.021277 (10825 2000);
PAINT ORANGE (10825 2000);
FORCEPROP 2 LAST CDS_LIB w_hdl
J 0
(10800 2100);
PAINT MONO (10800 2100);
DISPLAY INVISIBLE (10800 2100);
FORCEPROP 1 LAST CDS_LMAN_SYM_OUTLINE -50,25,50,-25
J 0
(10800 2100);
DISPLAY 0.468085 (10800 2100);
PAINT GREEN (10800 2100);
DISPLAY INVISIBLE (10800 2100);
FORCEPROP 1 LAST PATH I140
J 0
(10800 2100);
DISPLAY 0.617021 (10800 2100);
PAINT GREEN (10800 2100);
DISPLAY INVISIBLE (10800 2100);
FORCEPROP 1 LAST PART_NUMBER 78.22224.2BL
J 0
(10800 2100);
DISPLAY 0.617021 (10800 2100);
PAINT GREEN (10800 2100);
DISPLAY INVISIBLE (10800 2100);
FORCEPROP 1 LAST PACK_TYPE SMD-BCG6
J 0
(10800 2100);
DISPLAY 0.617021 (10800 2100);
PAINT GREEN (10800 2100);
DISPLAY INVISIBLE (10800 2100);
FORCEADD RES..1
(7850 4025);
FORCEPROP 1 LAST LOCATION RT44
J 0
(7800 4050);
DISPLAY 0.617021 (7800 4050);
PAINT AQUA (7800 4050);
FORCEPROP 1 LAST MATERIAL CHIP
J 0
(7850 3875);
DISPLAY 0.617021 (7850 3875);
PAINT SKYBLUE (7850 3875);
FORCEPROP 1 LAST TOLERANCE 5%
J 0
(7850 3925);
DISPLAY 0.617021 (7850 3925);
PAINT SKYBLUE (7850 3925);
FORCEPROP 1 LAST VALUE 0.0
J 2
(7825 3925);
DISPLAY 0.617021 (7825 3925);
PAINT SKYBLUE (7825 3925);
FORCEPROP 1 LAST WATTAGE 1/16W
J 2
(7825 3875);
DISPLAY 0.617021 (7825 3875);
PAINT SKYBLUE (7825 3875);
FORCEPROP 1 LAST PART_NUMBER G21497-005
J 0
(7750 3975);
DISPLAY 0.617021 (7750 3975);
PAINT BLUE (7750 3975);
FORCEPROP 1 LAST PACK_TYPE 0402
J 0
(7950 3875);
DISPLAY 0.617021 (7950 3875);
PAINT SKYBLUE (7950 3875);
FORCEPROP 2 LAST CDS_LIB mstr_discrete
J 0
(7850 4025);
PAINT MONO (7850 4025);
DISPLAY INVISIBLE (7850 4025);
FORCEPROP 1 LAST PATH I141
J 0
(7800 4175);
DISPLAY 0.978723 (7800 4175);
PAINT WHITE (7800 4175);
DISPLAY INVISIBLE (7800 4175);
FORCEPROP 2 LAST BOM_COST DEBUG
J 0
(7800 4225);
DISPLAY 1.021277 (7800 4225);
PAINT ORANGE (7800 4225);
DISPLAY INVISIBLE (7800 4225);
FORCEPROP 2 LAST ROOM BMC_DEBUG_HEADER
J 0
(7800 4175);
DISPLAY 1.021277 (7800 4175);
PAINT ORANGE (7800 4175);
DISPLAY INVISIBLE (7800 4175);
FORCEPROP 1 LASTPIN (7750 4025) $PN 1
J 0
(7762 4037);
DISPLAY 0.787234 (7762 4037);
PAINT ORANGE (7762 4037);
DISPLAY INVISIBLE (7762 4037);
FORCEPROP 1 LASTPIN (7950 4025) $PN 2
J 0
(7912 4037);
DISPLAY 0.787234 (7912 4037);
PAINT ORANGE (7912 4037);
DISPLAY INVISIBLE (7912 4037);
FORCEADD RES..1
(7900 2300);
FORCEPROP 1 LAST PACK_TYPE 0402
J 0
(8000 2150);
DISPLAY 0.617021 (8000 2150);
PAINT SKYBLUE (8000 2150);
FORCEPROP 1 LAST LOCATION RT46
J 0
(7850 2325);
DISPLAY 0.617021 (7850 2325);
PAINT AQUA (7850 2325);
FORCEPROP 1 LAST WATTAGE 1/16W
J 2
(7875 2150);
DISPLAY 0.617021 (7875 2150);
PAINT SKYBLUE (7875 2150);
FORCEPROP 1 LAST MATERIAL CHIP
J 0
(7900 2150);
DISPLAY 0.617021 (7900 2150);
PAINT SKYBLUE (7900 2150);
FORCEPROP 1 LAST TOLERANCE 5%
J 0
(7900 2200);
DISPLAY 0.617021 (7900 2200);
PAINT SKYBLUE (7900 2200);
FORCEPROP 1 LAST VALUE 0.0
J 2
(7875 2200);
DISPLAY 0.617021 (7875 2200);
PAINT SKYBLUE (7875 2200);
FORCEPROP 1 LAST PART_NUMBER G21497-005
J 0
(7800 2250);
DISPLAY 0.617021 (7800 2250);
PAINT BLUE (7800 2250);
FORCEPROP 2 LAST CDS_LIB mstr_discrete
J 0
(7900 2300);
PAINT MONO (7900 2300);
DISPLAY INVISIBLE (7900 2300);
FORCEPROP 1 LAST PATH I142
J 0
(7850 2450);
DISPLAY 0.978723 (7850 2450);
PAINT WHITE (7850 2450);
DISPLAY INVISIBLE (7850 2450);
FORCEPROP 2 LAST BOM_COST DEBUG
J 0
(7850 2500);
DISPLAY 1.021277 (7850 2500);
PAINT ORANGE (7850 2500);
DISPLAY INVISIBLE (7850 2500);
FORCEPROP 2 LAST ROOM BMC_DEBUG_HEADER
J 0
(7850 2450);
DISPLAY 1.021277 (7850 2450);
PAINT ORANGE (7850 2450);
DISPLAY INVISIBLE (7850 2450);
FORCEPROP 1 LASTPIN (7800 2300) $PN 1
J 0
(7812 2312);
DISPLAY 0.787234 (7812 2312);
PAINT ORANGE (7812 2312);
DISPLAY INVISIBLE (7812 2312);
FORCEPROP 1 LASTPIN (8000 2300) $PN 2
J 0
(7962 2312);
DISPLAY 0.787234 (7962 2312);
PAINT ORANGE (7962 2312);
DISPLAY INVISIBLE (7962 2312);
FORCEADD CAP..1
(7750 4550);
FORCEPROP 1 LAST PART_NUMBER A36096-155
J 0
(7800 4400);
DISPLAY 0.617021 (7800 4400);
PAINT BLUE (7800 4400);
FORCEPROP 1 LAST PACK_TYPE 0402
J 0
(7800 4350);
DISPLAY 0.617021 (7800 4350);
PAINT SKYBLUE (7800 4350);
FORCEPROP 1 LASTPIN (7750 4650) $PN 1
J 0
(7760 4630);
DISPLAY 0.617021 (7760 4630);
PAINT WHITE (7760 4630);
FORCEPROP 1 LAST LOCATION C7A8
J 0
(7800 4650);
DISPLAY 0.617021 (7800 4650);
PAINT AQUA (7800 4650);
FORCEPROP 1 LAST VALUE 0.22UF
J 0
(7800 4600);
DISPLAY 0.617021 (7800 4600);
PAINT SKYBLUE (7800 4600);
FORCEPROP 1 LAST TOLERANCE 10%
J 0
(7800 4500);
DISPLAY 0.617021 (7800 4500);
PAINT SKYBLUE (7800 4500);
FORCEPROP 1 LAST VOLTAGE 16V
J 0
(7800 4550);
DISPLAY 0.617021 (7800 4550);
PAINT SKYBLUE (7800 4550);
FORCEPROP 1 LAST MATERIAL X7R
J 0
(7800 4450);
DISPLAY 0.617021 (7800 4450);
PAINT SKYBLUE (7800 4450);
FORCEPROP 1 LASTPIN (7750 4450) $PN 2
J 0
(7760 4430);
DISPLAY 0.617021 (7760 4430);
PAINT WHITE (7760 4430);
FORCEPROP 2 LAST ROOM PVNN_PCH_STBY
J 0
(7800 4700);
DISPLAY 2.212766 (7800 4700);
PAINT WHITE (7800 4700);
DISPLAY INVISIBLE (7800 4700);
FORCEPROP 1 LAST PATH I16
J 0
(7800 4700);
DISPLAY 0.978723 (7800 4700);
PAINT WHITE (7800 4700);
DISPLAY INVISIBLE (7800 4700);
FORCEPROP 2 LAST CDS_LOCATION C7A8
J 0
(7800 4650);
DISPLAY 0.617021 (7800 4650);
PAINT AQUA (7800 4650);
DISPLAY INVISIBLE (7800 4650);
FORCEPROP 2 LAST SEC 1
J 0
(7800 4750);
DISPLAY 1.106383 (7800 4750);
PAINT MONO (7800 4750);
DISPLAY INVISIBLE (7800 4750);
FORCEPROP 2 LAST SEC_TYPE 0402
J 0
(7800 4750);
DISPLAY 1.659574 (7800 4750);
PAINT ORANGE (7800 4750);
DISPLAY INVISIBLE (7800 4750);
FORCEPROP 2 LAST CDS_LIB mstr_discrete
J 0
(7750 4550);
DISPLAY 1.617021 (7750 4550);
PAINT ORANGE (7750 4550);
DISPLAY INVISIBLE (7750 4550);
FORCEADD CAP_A..1
R 2
(7625 4550);
FORCEPROP 1 LAST MATERIAL X6S
J 2
(7575 4450);
DISPLAY 0.617021 (7575 4450);
PAINT SKYBLUE (7575 4450);
FORCEPROP 1 LASTPIN (7625 4650) $PN 1
J 2
(7615 4630);
DISPLAY 0.617021 (7615 4630);
PAINT WHITE (7615 4630);
FORCEPROP 1 LAST LOCATION C3L1
J 2
(7575 4650);
DISPLAY 0.617021 (7575 4650);
PAINT AQUA (7575 4650);
FORCEPROP 1 LAST VALUE 1.0UF
J 2
(7575 4600);
DISPLAY 0.617021 (7575 4600);
PAINT SKYBLUE (7575 4600);
FORCEPROP 1 LASTPIN (7625 4450) $PN 2
J 2
(7615 4430);
DISPLAY 0.617021 (7615 4430);
PAINT WHITE (7615 4430);
FORCEPROP 1 LAST VOLTAGE 6.3V
J 2
(7575 4550);
DISPLAY 0.617021 (7575 4550);
PAINT SKYBLUE (7575 4550);
FORCEPROP 1 LAST TOLERANCE 10%
J 2
(7575 4500);
DISPLAY 0.617021 (7575 4500);
PAINT SKYBLUE (7575 4500);
FORCEPROP 1 LAST PACK_TYPE 0402V
J 2
(7575 4350);
DISPLAY 0.617021 (7575 4350);
PAINT SKYBLUE (7575 4350);
FORCEPROP 1 LAST PART_NUMBER D97712-004
J 2
(7575 4400);
DISPLAY 0.617021 (7575 4400);
PAINT BLUE (7575 4400);
FORCEPROP 2 LAST SEC_TYPE 0402V
J 0
(7575 4750);
DISPLAY 1.659574 (7575 4750);
PAINT ORANGE (7575 4750);
DISPLAY INVISIBLE (7575 4750);
FORCEPROP 2 LAST CDS_SEC 1
J 0
(7575 4700);
PAINT ORANGE (7575 4700);
DISPLAY INVISIBLE (7575 4700);
FORCEPROP 2 LAST CDS_LOCATION C3L1
J 2
(7575 4650);
DISPLAY 0.617021 (7575 4650);
PAINT AQUA (7575 4650);
DISPLAY INVISIBLE (7575 4650);
FORCEPROP 2 LAST ROOM PVNN_PCH_STBY
J 0
(7575 4700);
DISPLAY 2.212766 (7575 4700);
PAINT WHITE (7575 4700);
DISPLAY INVISIBLE (7575 4700);
FORCEPROP 1 LAST PATH I17
J 2
(7575 4700);
DISPLAY 0.978723 (7575 4700);
PAINT WHITE (7575 4700);
DISPLAY INVISIBLE (7575 4700);
FORCEPROP 2 LAST SEC 1
J 0
(7575 4750);
DISPLAY 1.106383 (7575 4750);
PAINT MONO (7575 4750);
DISPLAY INVISIBLE (7575 4750);
FORCEPROP 2 LAST CDS_LIB dev_discrete
J 0
(7625 4550);
PAINT ORANGE (7625 4550);
DISPLAY INVISIBLE (7625 4550);
FORCEADD CAP..1
(6925 4500);
FORCEPROP 1 LAST PACK_TYPE 0402
J 0
(6975 4300);
DISPLAY 0.617021 (6975 4300);
PAINT SKYBLUE (6975 4300);
FORCEPROP 1 LAST PART_NUMBER D97712-011
J 0
(6975 4350);
DISPLAY 0.617021 (6975 4350);
PAINT BLUE (6975 4350);
FORCEPROP 1 LAST VALUE 1.0UF
J 0
(6975 4550);
DISPLAY 0.617021 (6975 4550);
PAINT SKYBLUE (6975 4550);
FORCEPROP 1 LAST LOCATION C7A6
J 0
(6975 4600);
DISPLAY 0.617021 (6975 4600);
PAINT AQUA (6975 4600);
FORCEPROP 1 LASTPIN (6925 4600) $PN 1
J 0
(6935 4580);
DISPLAY 0.617021 (6935 4580);
PAINT WHITE (6935 4580);
FORCEPROP 1 LASTPIN (6925 4400) $PN 2
J 0
(6935 4380);
DISPLAY 0.617021 (6935 4380);
PAINT WHITE (6935 4380);
FORCEPROP 1 LAST MATERIAL X6S
J 0
(6975 4400);
DISPLAY 0.617021 (6975 4400);
PAINT SKYBLUE (6975 4400);
FORCEPROP 1 LAST VOLTAGE 16V
J 0
(6975 4500);
DISPLAY 0.617021 (6975 4500);
PAINT SKYBLUE (6975 4500);
FORCEPROP 1 LAST TOLERANCE 10%
J 0
(6975 4450);
DISPLAY 0.617021 (6975 4450);
PAINT SKYBLUE (6975 4450);
FORCEPROP 2 LAST ROOM P1V05_PCH_STBY_VR
J 0
(6975 4650);
DISPLAY 2.212766 (6975 4650);
PAINT WHITE (6975 4650);
DISPLAY INVISIBLE (6975 4650);
FORCEPROP 1 LAST PATH I19
J 0
(6975 4650);
DISPLAY 0.978723 (6975 4650);
PAINT WHITE (6975 4650);
DISPLAY INVISIBLE (6975 4650);
FORCEPROP 2 LAST SEC 1
J 0
(6975 4700);
DISPLAY 1.106383 (6975 4700);
PAINT MONO (6975 4700);
DISPLAY INVISIBLE (6975 4700);
FORCEPROP 2 LAST SEC_TYPE 0402
J 0
(6975 4700);
DISPLAY 1.659574 (6975 4700);
PAINT ORANGE (6975 4700);
DISPLAY INVISIBLE (6975 4700);
FORCEPROP 2 LAST CDS_LOCATION C7A6
J 0
(6975 4600);
DISPLAY 0.617021 (6975 4600);
PAINT AQUA (6975 4600);
DISPLAY INVISIBLE (6975 4600);
FORCEPROP 2 LAST CDS_LIB mstr_discrete
J 0
(6925 4500);
DISPLAY 1.617021 (6925 4500);
PAINT ORANGE (6925 4500);
DISPLAY INVISIBLE (6925 4500);
FORCEADD OFFPAGE..2
(11275 4800);
FORCEPROP 2 LAST $XR0 235 
J 0
(11464 4800);
DISPLAY 0.638298 (11464 4800);
PAINT MONO (11464 4800);
FORCEPROP 2 LAST PATH I2
J 0
(11475 4850);
DISPLAY 1.021277 (11475 4850);
PAINT ORANGE (11475 4850);
DISPLAY INVISIBLE (11475 4850);
FORCEPROP 2 LAST CDS_LIB mstr_standard
J 0
(11275 4800);
DISPLAY 1.617021 (11275 4800);
PAINT ORANGE (11275 4800);
DISPLAY INVISIBLE (11275 4800);
FORCEPROP 2 LAST BOM_COST PROC_VRD_PVCCIO_CPU0
J 0
(11475 4850);
DISPLAY 2.340426 (11475 4850);
PAINT WHITE (11475 4850);
DISPLAY INVISIBLE (11475 4850);
FORCEPROP 2 LAST ROOM PVCCIO_CPU0
J 0
(10875 4875);
DISPLAY 3.127660 (10875 4875);
PAINT WHITE (10875 4875);
DISPLAY INVISIBLE (10875 4875);
FORCEPROP 1 LAST OFFPAGE TRUE
J 0
(11600 4675);
PAINT GREEN (11600 4675);
DISPLAY INVISIBLE (11600 4675);
FORCEPROP 1 LAST COMMENT_BODY TRUE
J 0
(11230 4705);
DISPLAY 2.787234 (11230 4705);
PAINT PEACH (11230 4705);
DISPLAY INVISIBLE (11230 4705);
FORCEADD CAP_A..1
(6550 4525);
FORCEPROP 1 LAST MATERIAL X7R
J 0
(6600 4425);
DISPLAY 0.617021 (6600 4425);
PAINT SKYBLUE (6600 4425);
FORCEPROP 1 LAST VOLTAGE 16V
J 0
(6600 4525);
DISPLAY 0.617021 (6600 4525);
PAINT SKYBLUE (6600 4525);
FORCEPROP 1 LAST PACK_TYPE 0402V
J 0
(6600 4325);
DISPLAY 0.617021 (6600 4325);
PAINT SKYBLUE (6600 4325);
FORCEPROP 1 LAST TOLERANCE 10%
J 0
(6600 4475);
DISPLAY 0.617021 (6600 4475);
PAINT SKYBLUE (6600 4475);
FORCEPROP 1 LAST VALUE 0.1UF
J 0
(6600 4575);
DISPLAY 0.617021 (6600 4575);
PAINT SKYBLUE (6600 4575);
FORCEPROP 1 LAST PART_NUMBER A36096-030
J 0
(6600 4375);
DISPLAY 0.617021 (6600 4375);
PAINT BLUE (6600 4375);
FORCEPROP 1 LAST LOCATION C7A39
J 0
(6600 4625);
DISPLAY 0.617021 (6600 4625);
PAINT AQUA (6600 4625);
FORCEPROP 1 LASTPIN (6550 4625) $PN 1
J 0
(6560 4605);
DISPLAY 0.617021 (6560 4605);
PAINT WHITE (6560 4605);
FORCEPROP 1 LASTPIN (6550 4425) $PN 2
J 0
(6560 4405);
DISPLAY 0.617021 (6560 4405);
PAINT WHITE (6560 4405);
FORCEPROP 1 LAST PATH I20
J 0
(6600 4675);
DISPLAY 0.978723 (6600 4675);
PAINT WHITE (6600 4675);
DISPLAY INVISIBLE (6600 4675);
FORCEPROP 2 LAST ROOM PVNN_PCH_STBY
J 0
(6600 4675);
DISPLAY 2.212766 (6600 4675);
PAINT WHITE (6600 4675);
DISPLAY INVISIBLE (6600 4675);
FORCEPROP 2 LAST CDS_SEC 1
J 0
(6600 4675);
PAINT ORANGE (6600 4675);
DISPLAY INVISIBLE (6600 4675);
FORCEPROP 2 LAST SEC_TYPE 0402V
J 0
(6600 4725);
DISPLAY 1.659574 (6600 4725);
PAINT ORANGE (6600 4725);
DISPLAY INVISIBLE (6600 4725);
FORCEPROP 2 LAST SEC 1
J 0
(6600 4725);
DISPLAY 1.106383 (6600 4725);
PAINT MONO (6600 4725);
DISPLAY INVISIBLE (6600 4725);
FORCEPROP 2 LAST CDS_LIB dev_discrete
J 0
(6550 4525);
PAINT ORANGE (6550 4525);
DISPLAY INVISIBLE (6550 4525);
FORCEADD CAP..1
R 2
(6825 3825);
FORCEPROP 1 LASTPIN (6825 3725) $PN 2
J 2
(6815 3705);
DISPLAY 0.617021 (6815 3705);
PAINT ORANGE (6815 3705);
FORCEPROP 1 LAST PART_NUMBER A36096-104
J 2
(6775 3675);
DISPLAY 0.617021 (6775 3675);
PAINT BLUE (6775 3675);
FORCEPROP 1 LAST VALUE 0.220UF
J 2
(6775 3875);
DISPLAY 0.617021 (6775 3875);
PAINT SKYBLUE (6775 3875);
FORCEPROP 1 LAST TOLERANCE 10%
J 2
(6775 3775);
DISPLAY 0.617021 (6775 3775);
PAINT SKYBLUE (6775 3775);
FORCEPROP 1 LAST PACK_TYPE 0402
J 2
(6775 3625);
DISPLAY 0.617021 (6775 3625);
PAINT SKYBLUE (6775 3625);
FORCEPROP 1 LAST VOLTAGE 16V
J 2
(6775 3825);
DISPLAY 0.617021 (6775 3825);
PAINT SKYBLUE (6775 3825);
FORCEPROP 1 LAST MATERIAL X7R
J 2
(6775 3725);
DISPLAY 0.617021 (6775 3725);
PAINT SKYBLUE (6775 3725);
FORCEPROP 1 LAST LOCATION C7A43
J 2
(6775 3925);
DISPLAY 0.617021 (6775 3925);
PAINT AQUA (6775 3925);
FORCEPROP 1 LASTPIN (6825 3925) $PN 1
J 2
(6815 3905);
DISPLAY 0.617021 (6815 3905);
PAINT ORANGE (6815 3905);
FORCEPROP 2 LAST CDS_LIB mstr_discrete
J 0
(6825 3825);
PAINT ORANGE (6825 3825);
DISPLAY INVISIBLE (6825 3825);
FORCEPROP 0 LAST SPOF TRUE
J 0
(6775 4025);
DISPLAY 1.021277 (6775 4025);
PAINT ORANGE (6775 4025);
DISPLAY INVISIBLE (6775 4025);
FORCEPROP 2 LAST SEC_TYPE 0402
J 0
(6775 4025);
DISPLAY 1.021277 (6775 4025);
PAINT ORANGE (6775 4025);
DISPLAY INVISIBLE (6775 4025);
FORCEPROP 2 LAST SEC 1
J 0
(6775 4025);
DISPLAY 0.680851 (6775 4025);
PAINT MONO (6775 4025);
DISPLAY INVISIBLE (6775 4025);
FORCEPROP 1 LAST PATH I21
J 2
(6775 3975);
DISPLAY 0.978723 (6775 3975);
PAINT WHITE (6775 3975);
DISPLAY INVISIBLE (6775 3975);
FORCEPROP 2 LAST ROOM PVNN_PCH_STBY
J 0
(6775 3975);
DISPLAY 2.212766 (6775 3975);
PAINT WHITE (6775 3975);
DISPLAY INVISIBLE (6775 3975);
FORCEADD CAP..1
(6300 4500);
FORCEPROP 1 LAST MATERIAL X6S
J 0
(6350 4400);
DISPLAY 0.617021 (6350 4400);
PAINT SKYBLUE (6350 4400);
FORCEPROP 1 LAST VOLTAGE 16V
J 0
(6350 4500);
DISPLAY 0.617021 (6350 4500);
PAINT SKYBLUE (6350 4500);
FORCEPROP 1 LAST VALUE 1.0UF
J 0
(6350 4550);
DISPLAY 0.617021 (6350 4550);
PAINT SKYBLUE (6350 4550);
FORCEPROP 1 LAST PART_NUMBER D97712-011
J 0
(6350 4350);
DISPLAY 0.617021 (6350 4350);
PAINT BLUE (6350 4350);
FORCEPROP 1 LASTPIN (6300 4600) $PN 1
J 0
(6310 4580);
DISPLAY 0.617021 (6310 4580);
PAINT WHITE (6310 4580);
FORCEPROP 1 LASTPIN (6300 4400) $PN 2
J 0
(6310 4380);
DISPLAY 0.617021 (6310 4380);
PAINT WHITE (6310 4380);
FORCEPROP 1 LAST TOLERANCE 10%
J 0
(6350 4450);
DISPLAY 0.617021 (6350 4450);
PAINT SKYBLUE (6350 4450);
FORCEPROP 1 LAST LOCATION C7A7
J 0
(6350 4600);
DISPLAY 0.617021 (6350 4600);
PAINT AQUA (6350 4600);
FORCEPROP 1 LAST PACK_TYPE 0402
J 0
(6350 4300);
DISPLAY 0.617021 (6350 4300);
PAINT SKYBLUE (6350 4300);
FORCEPROP 2 LAST SEC_TYPE 0402
J 0
(6350 4700);
DISPLAY 1.659574 (6350 4700);
PAINT ORANGE (6350 4700);
DISPLAY INVISIBLE (6350 4700);
FORCEPROP 2 LAST SEC 1
J 0
(6350 4700);
DISPLAY 1.106383 (6350 4700);
PAINT MONO (6350 4700);
DISPLAY INVISIBLE (6350 4700);
FORCEPROP 1 LAST PATH I22
J 0
(6350 4650);
DISPLAY 0.978723 (6350 4650);
PAINT WHITE (6350 4650);
DISPLAY INVISIBLE (6350 4650);
FORCEPROP 2 LAST ROOM PVNN_PCH_STBY
J 0
(6350 4650);
DISPLAY 2.212766 (6350 4650);
PAINT WHITE (6350 4650);
DISPLAY INVISIBLE (6350 4650);
FORCEPROP 2 LAST CDS_LOCATION C7A7
J 0
(6350 4600);
DISPLAY 0.617021 (6350 4600);
PAINT AQUA (6350 4600);
DISPLAY INVISIBLE (6350 4600);
FORCEPROP 2 LAST CDS_LIB mstr_discrete
J 0
(6300 4500);
DISPLAY 1.617021 (6300 4500);
PAINT ORANGE (6300 4500);
DISPLAY INVISIBLE (6300 4500);
FORCEADD CAP..1
(6050 4525);
FORCEPROP 1 LAST MATERIAL X6S
J 0
(6100 4425);
DISPLAY 0.617021 (6100 4425);
PAINT SKYBLUE (6100 4425);
FORCEPROP 1 LAST VOLTAGE 16V
J 0
(6100 4525);
DISPLAY 0.617021 (6100 4525);
PAINT SKYBLUE (6100 4525);
FORCEPROP 1 LAST PACK_TYPE 0805
J 0
(6100 4325);
DISPLAY 0.617021 (6100 4325);
PAINT SKYBLUE (6100 4325);
FORCEPROP 1 LAST TOLERANCE 10%
J 0
(6100 4475);
DISPLAY 0.617021 (6100 4475);
PAINT SKYBLUE (6100 4475);
FORCEPROP 1 LAST VALUE 10UF
J 0
(6100 4575);
DISPLAY 0.617021 (6100 4575);
PAINT SKYBLUE (6100 4575);
FORCEPROP 1 LAST PART_NUMBER C95333-007
J 0
(6100 4375);
DISPLAY 0.617021 (6100 4375);
PAINT BLUE (6100 4375);
FORCEPROP 1 LAST LOCATION C3L12
J 0
(6100 4625);
DISPLAY 0.617021 (6100 4625);
PAINT AQUA (6100 4625);
FORCEPROP 1 LASTPIN (6050 4625) $PN 1
J 0
(6060 4605);
DISPLAY 0.617021 (6060 4605);
PAINT WHITE (6060 4605);
FORCEPROP 1 LASTPIN (6050 4425) $PN 2
J 0
(6060 4405);
DISPLAY 0.617021 (6060 4405);
PAINT WHITE (6060 4405);
FORCEPROP 2 LAST SEC_TYPE 0805
J 0
(6100 4725);
DISPLAY 1.659574 (6100 4725);
PAINT ORANGE (6100 4725);
DISPLAY INVISIBLE (6100 4725);
FORCEPROP 2 LAST SEC 1
J 0
(6100 4725);
DISPLAY 1.106383 (6100 4725);
PAINT MONO (6100 4725);
DISPLAY INVISIBLE (6100 4725);
FORCEPROP 2 LAST CDS_LOCATION C3L12
J 0
(6100 4625);
DISPLAY 0.617021 (6100 4625);
PAINT AQUA (6100 4625);
DISPLAY INVISIBLE (6100 4625);
FORCEPROP 1 LAST PATH I23
J 0
(6100 4675);
DISPLAY 0.978723 (6100 4675);
PAINT WHITE (6100 4675);
DISPLAY INVISIBLE (6100 4675);
FORCEPROP 2 LAST ROOM PVNN_PCH_STBY
J 0
(6100 4675);
DISPLAY 2.212766 (6100 4675);
PAINT WHITE (6100 4675);
DISPLAY INVISIBLE (6100 4675);
FORCEPROP 2 LAST CDS_LIB mstr_discrete
J 0
(6050 4525);
DISPLAY 1.617021 (6050 4525);
PAINT ORANGE (6050 4525);
DISPLAY INVISIBLE (6050 4525);
FORCEADD CAP..1
(5825 4500);
FORCEPROP 1 LAST PART_NUMBER C95333-007
J 0
(5875 4350);
DISPLAY 0.617021 (5875 4350);
PAINT BLUE (5875 4350);
FORCEPROP 1 LAST LOCATION C3L11
J 0
(5875 4600);
DISPLAY 0.617021 (5875 4600);
PAINT AQUA (5875 4600);
FORCEPROP 1 LAST MATERIAL X6S
J 0
(5875 4400);
DISPLAY 0.617021 (5875 4400);
PAINT SKYBLUE (5875 4400);
FORCEPROP 1 LAST VOLTAGE 16V
J 0
(5875 4500);
DISPLAY 0.617021 (5875 4500);
PAINT SKYBLUE (5875 4500);
FORCEPROP 1 LAST PACK_TYPE 0805
J 0
(5875 4300);
DISPLAY 0.617021 (5875 4300);
PAINT SKYBLUE (5875 4300);
FORCEPROP 1 LAST TOLERANCE 10%
J 0
(5875 4450);
DISPLAY 0.617021 (5875 4450);
PAINT SKYBLUE (5875 4450);
FORCEPROP 1 LAST VALUE 10UF
J 0
(5875 4550);
DISPLAY 0.617021 (5875 4550);
PAINT SKYBLUE (5875 4550);
FORCEPROP 1 LASTPIN (5825 4400) $PN 2
J 0
(5835 4380);
DISPLAY 0.617021 (5835 4380);
PAINT WHITE (5835 4380);
FORCEPROP 1 LASTPIN (5825 4600) $PN 1
J 0
(5835 4580);
DISPLAY 0.617021 (5835 4580);
PAINT WHITE (5835 4580);
FORCEPROP 2 LAST SEC_TYPE 0805
J 0
(5875 4700);
DISPLAY 1.659574 (5875 4700);
PAINT ORANGE (5875 4700);
DISPLAY INVISIBLE (5875 4700);
FORCEPROP 2 LAST SEC 1
J 0
(5875 4700);
DISPLAY 1.106383 (5875 4700);
PAINT MONO (5875 4700);
DISPLAY INVISIBLE (5875 4700);
FORCEPROP 1 LAST PATH I24
J 0
(5875 4650);
DISPLAY 0.978723 (5875 4650);
PAINT WHITE (5875 4650);
DISPLAY INVISIBLE (5875 4650);
FORCEPROP 2 LAST ROOM PVNN_PCH_STBY
J 0
(5875 4650);
DISPLAY 2.212766 (5875 4650);
PAINT WHITE (5875 4650);
DISPLAY INVISIBLE (5875 4650);
FORCEPROP 2 LAST CDS_LOCATION C3L11
J 0
(5875 4600);
DISPLAY 0.617021 (5875 4600);
PAINT AQUA (5875 4600);
DISPLAY INVISIBLE (5875 4600);
FORCEPROP 2 LAST CDS_LIB mstr_discrete
J 0
(5825 4500);
DISPLAY 1.617021 (5825 4500);
PAINT ORANGE (5825 4500);
DISPLAY INVISIBLE (5825 4500);
FORCEADD OFFPAGE..1
(6400 4150);
FORCEPROP 2 LAST $XR0 235 
J 0
(6148 4150);
DISPLAY 0.638298 (6148 4150);
PAINT MONO (6148 4150);
FORCEPROP 2 LAST CDS_LIB mstr_standard
J 0
(6400 4150);
DISPLAY 1.617021 (6400 4150);
PAINT ORANGE (6400 4150);
DISPLAY INVISIBLE (6400 4150);
FORCEPROP 2 LAST BOM_COST PROC_VRD_PVCCIO_CPU0
J 0
(6150 4200);
DISPLAY 2.340426 (6150 4200);
PAINT WHITE (6150 4200);
DISPLAY INVISIBLE (6150 4200);
FORCEPROP 2 LAST PATH I25
J 0
(6150 4200);
DISPLAY 1.021277 (6150 4200);
PAINT ORANGE (6150 4200);
DISPLAY INVISIBLE (6150 4200);
FORCEPROP 2 LAST ROOM PVCCIO_CPU0
J 0
(6000 4225);
DISPLAY 3.127660 (6000 4225);
PAINT WHITE (6000 4225);
DISPLAY INVISIBLE (6000 4225);
FORCEPROP 1 LAST OFFPAGE TRUE
J 0
(6725 4025);
PAINT GREEN (6725 4025);
DISPLAY INVISIBLE (6725 4025);
FORCEPROP 1 LAST COMMENT_BODY TRUE
J 0
(6525 4050);
DISPLAY 2.723404 (6525 4050);
PAINT PEACH (6525 4050);
DISPLAY INVISIBLE (6525 4050);
FORCEADD CAP..1
(5575 4525);
FORCEPROP 1 LAST MATERIAL X6S
J 0
(5625 4425);
DISPLAY 0.617021 (5625 4425);
PAINT SKYBLUE (5625 4425);
FORCEPROP 1 LAST VOLTAGE 16V
J 0
(5625 4525);
DISPLAY 0.617021 (5625 4525);
PAINT SKYBLUE (5625 4525);
FORCEPROP 1 LAST PACK_TYPE 0805
J 0
(5625 4325);
DISPLAY 0.617021 (5625 4325);
PAINT SKYBLUE (5625 4325);
FORCEPROP 1 LAST TOLERANCE 10%
J 0
(5625 4475);
DISPLAY 0.617021 (5625 4475);
PAINT SKYBLUE (5625 4475);
FORCEPROP 1 LAST VALUE 10UF
J 0
(5625 4575);
DISPLAY 0.617021 (5625 4575);
PAINT SKYBLUE (5625 4575);
FORCEPROP 1 LAST PART_NUMBER C95333-007
J 0
(5625 4375);
DISPLAY 0.617021 (5625 4375);
PAINT BLUE (5625 4375);
FORCEPROP 1 LASTPIN (5575 4625) $PN 1
J 0
(5585 4605);
DISPLAY 0.617021 (5585 4605);
PAINT WHITE (5585 4605);
FORCEPROP 1 LASTPIN (5575 4425) $PN 2
J 0
(5585 4405);
DISPLAY 0.617021 (5585 4405);
PAINT WHITE (5585 4405);
FORCEPROP 1 LAST LOCATION C3L8
J 0
(5625 4625);
DISPLAY 0.617021 (5625 4625);
PAINT AQUA (5625 4625);
FORCEPROP 2 LAST ROOM PVNN_PCH_STBY
J 0
(5625 4675);
DISPLAY 2.212766 (5625 4675);
PAINT WHITE (5625 4675);
DISPLAY INVISIBLE (5625 4675);
FORCEPROP 2 LAST SEC 1
J 0
(5625 4725);
DISPLAY 1.106383 (5625 4725);
PAINT MONO (5625 4725);
DISPLAY INVISIBLE (5625 4725);
FORCEPROP 2 LAST SEC_TYPE 0805
J 0
(5625 4725);
DISPLAY 1.659574 (5625 4725);
PAINT ORANGE (5625 4725);
DISPLAY INVISIBLE (5625 4725);
FORCEPROP 1 LAST PATH I26
J 0
(5625 4675);
DISPLAY 0.978723 (5625 4675);
PAINT WHITE (5625 4675);
DISPLAY INVISIBLE (5625 4675);
FORCEPROP 2 LAST CDS_LOCATION C3L8
J 0
(5625 4625);
DISPLAY 0.617021 (5625 4625);
PAINT AQUA (5625 4625);
DISPLAY INVISIBLE (5625 4625);
FORCEPROP 2 LAST CDS_LIB mstr_discrete
J 0
(5575 4525);
DISPLAY 1.617021 (5575 4525);
PAINT ORANGE (5575 4525);
DISPLAY INVISIBLE (5575 4525);
FORCEADD GND..1
(5575 4075);
FORCEPROP 3 LASTPIN (5575 4125) SIG_NAME GND\g
J 0
(5585 4135);
DISPLAY 0.659574 (5585 4135);
PAINT MONO (5585 4135);
DISPLAY INVISIBLE (5585 4135);
FORCEPROP 2 LAST BOM_COST PROC_VRD_PVCCIO_CPU0
J 0
(5200 4150);
DISPLAY 2.340426 (5200 4150);
PAINT WHITE (5200 4150);
DISPLAY INVISIBLE (5200 4150);
FORCEPROP 2 LAST ROOM PVCCIO_CPU0
J 0
(5025 4150);
DISPLAY 3.127660 (5025 4150);
PAINT WHITE (5025 4150);
DISPLAY INVISIBLE (5025 4150);
FORCEPROP 1 LAST PATH I27
J 0
(5650 4075);
DISPLAY 0.872340 (5650 4075);
PAINT AQUA (5650 4075);
DISPLAY INVISIBLE (5650 4075);
FORCEPROP 2 LAST CDS_LIB mstr_symbols
J 0
(5575 4075);
DISPLAY 1.617021 (5575 4075);
PAINT ORANGE (5575 4075);
DISPLAY INVISIBLE (5575 4075);
FORCEPROP 1 LAST SIZE 1B
J 0
(5650 4025);
DISPLAY 2.787234 (5650 4025);
PAINT GREEN (5650 4025);
DISPLAY INVISIBLE (5650 4025);
FORCEPROP 1 LAST VOLTAGE 0.0V
J 0
(5530 4032);
DISPLAY 0.340426 (5530 4032);
PAINT SKYBLUE (5530 4032);
DISPLAY INVISIBLE (5530 4032);
FORCEPROP 1 LAST BODY_TYPE PLUMBING
J 0
(5530 4032);
DISPLAY 0.340426 (5530 4032);
PAINT GREEN (5530 4032);
DISPLAY INVISIBLE (5530 4032);
FORCEPROP 1 LAST HDL_POWER GND
J 0
(5575 4225);
DISPLAY 2.787234 (5575 4225);
PAINT GREEN (5575 4225);
DISPLAY INVISIBLE (5575 4225);
FORCEADD GND..1
(5600 2350);
FORCEPROP 3 LASTPIN (5600 2400) SIG_NAME GND\g
J 0
(5610 2410);
DISPLAY 0.659574 (5610 2410);
PAINT MONO (5610 2410);
DISPLAY INVISIBLE (5610 2410);
FORCEPROP 1 LAST SIZE 1B
J 0
(5675 2300);
DISPLAY 2.787234 (5675 2300);
PAINT GREEN (5675 2300);
DISPLAY INVISIBLE (5675 2300);
FORCEPROP 1 LAST PATH I28
J 0
(5675 2350);
DISPLAY 0.872340 (5675 2350);
PAINT AQUA (5675 2350);
DISPLAY INVISIBLE (5675 2350);
FORCEPROP 2 LAST CDS_LIB mstr_symbols
J 0
(5600 2350);
DISPLAY 1.617021 (5600 2350);
PAINT ORANGE (5600 2350);
DISPLAY INVISIBLE (5600 2350);
FORCEPROP 1 LAST VOLTAGE 0.0V
J 0
(5555 2307);
DISPLAY 0.340426 (5555 2307);
PAINT SKYBLUE (5555 2307);
DISPLAY INVISIBLE (5555 2307);
FORCEPROP 2 LAST BOM_COST PROC_VRD_PVCCIO_CPU0
J 0
(5225 2425);
DISPLAY 2.340426 (5225 2425);
PAINT WHITE (5225 2425);
DISPLAY INVISIBLE (5225 2425);
FORCEPROP 2 LAST ROOM PVCCIO_CPU0
J 0
(5050 2425);
DISPLAY 3.127660 (5050 2425);
PAINT WHITE (5050 2425);
DISPLAY INVISIBLE (5050 2425);
FORCEPROP 1 LAST BODY_TYPE PLUMBING
J 0
(5555 2307);
DISPLAY 0.340426 (5555 2307);
PAINT GREEN (5555 2307);
DISPLAY INVISIBLE (5555 2307);
FORCEPROP 1 LAST HDL_POWER GND
J 0
(5600 2500);
DISPLAY 2.787234 (5600 2500);
PAINT GREEN (5600 2500);
DISPLAY INVISIBLE (5600 2500);
FORCEADD CAP..1
(5600 2825);
FORCEPROP 1 LAST PART_NUMBER C95333-007
J 0
(5650 2675);
DISPLAY 0.617021 (5650 2675);
PAINT BLUE (5650 2675);
FORCEPROP 1 LAST VALUE 10UF
J 0
(5650 2875);
DISPLAY 0.617021 (5650 2875);
PAINT SKYBLUE (5650 2875);
FORCEPROP 1 LAST LOCATION C3L9
J 0
(5650 2925);
DISPLAY 0.617021 (5650 2925);
PAINT AQUA (5650 2925);
FORCEPROP 1 LAST VOLTAGE 16V
J 0
(5650 2825);
DISPLAY 0.617021 (5650 2825);
PAINT SKYBLUE (5650 2825);
FORCEPROP 1 LAST TOLERANCE 10%
J 0
(5650 2775);
DISPLAY 0.617021 (5650 2775);
PAINT SKYBLUE (5650 2775);
FORCEPROP 1 LAST PACK_TYPE 0805
J 0
(5650 2625);
DISPLAY 0.617021 (5650 2625);
PAINT SKYBLUE (5650 2625);
FORCEPROP 1 LAST MATERIAL X6S
J 0
(5650 2725);
DISPLAY 0.617021 (5650 2725);
PAINT SKYBLUE (5650 2725);
FORCEPROP 1 LASTPIN (5600 2925) $PN 1
J 0
(5610 2905);
DISPLAY 0.617021 (5610 2905);
PAINT WHITE (5610 2905);
FORCEPROP 1 LASTPIN (5600 2725) $PN 2
J 0
(5610 2705);
DISPLAY 0.617021 (5610 2705);
PAINT WHITE (5610 2705);
FORCEPROP 2 LAST SEC_TYPE 0805
J 0
(5650 3025);
DISPLAY 1.659574 (5650 3025);
PAINT ORANGE (5650 3025);
DISPLAY INVISIBLE (5650 3025);
FORCEPROP 2 LAST SEC 1
J 0
(5650 3025);
DISPLAY 1.106383 (5650 3025);
PAINT MONO (5650 3025);
DISPLAY INVISIBLE (5650 3025);
FORCEPROP 2 LAST CDS_LOCATION C3L9
J 0
(5650 2925);
DISPLAY 0.617021 (5650 2925);
PAINT AQUA (5650 2925);
DISPLAY INVISIBLE (5650 2925);
FORCEPROP 2 LAST ROOM P1V05_PCH_STBY_VR
J 0
(5650 2975);
DISPLAY 2.212766 (5650 2975);
PAINT WHITE (5650 2975);
DISPLAY INVISIBLE (5650 2975);
FORCEPROP 1 LAST PATH I29
J 0
(5650 2975);
DISPLAY 0.978723 (5650 2975);
PAINT WHITE (5650 2975);
DISPLAY INVISIBLE (5650 2975);
FORCEPROP 2 LAST CDS_LIB mstr_discrete
J 0
(5600 2825);
DISPLAY 1.617021 (5600 2825);
PAINT ORANGE (5600 2825);
DISPLAY INVISIBLE (5600 2825);
FORCEADD OFFPAGE..2
(11300 5125);
FORCEPROP 2 LAST $XR0 235 
J 0
(11489 5125);
DISPLAY 0.638298 (11489 5125);
PAINT MONO (11489 5125);
FORCEPROP 2 LAST PATH I3
J 0
(11500 5175);
DISPLAY 1.021277 (11500 5175);
PAINT ORANGE (11500 5175);
DISPLAY INVISIBLE (11500 5175);
FORCEPROP 2 LAST CDS_LIB mstr_standard
J 0
(11300 5125);
DISPLAY 1.617021 (11300 5125);
PAINT ORANGE (11300 5125);
DISPLAY INVISIBLE (11300 5125);
FORCEPROP 2 LAST BOM_COST PROC_VRD_PVCCIO_CPU0
J 0
(11500 5175);
DISPLAY 2.340426 (11500 5175);
PAINT WHITE (11500 5175);
DISPLAY INVISIBLE (11500 5175);
FORCEPROP 2 LAST ROOM PVCCIO_CPU0
J 0
(10900 5200);
DISPLAY 3.127660 (10900 5200);
PAINT WHITE (10900 5200);
DISPLAY INVISIBLE (10900 5200);
FORCEPROP 1 LAST OFFPAGE TRUE
J 0
(11625 5000);
PAINT GREEN (11625 5000);
DISPLAY INVISIBLE (11625 5000);
FORCEPROP 1 LAST COMMENT_BODY TRUE
J 0
(11255 5030);
DISPLAY 2.787234 (11255 5030);
PAINT PEACH (11255 5030);
DISPLAY INVISIBLE (11255 5030);
FORCEADD OFFPAGE..1
(6450 2400);
FORCEPROP 2 LAST $XR0 235 
J 0
(6168 2400);
DISPLAY 0.638298 (6168 2400);
PAINT MONO (6168 2400);
FORCEPROP 2 LAST CDS_LIB mstr_standard
J 0
(6450 2400);
DISPLAY 1.617021 (6450 2400);
PAINT ORANGE (6450 2400);
DISPLAY INVISIBLE (6450 2400);
FORCEPROP 2 LAST PATH I30
J 0
(6200 2450);
DISPLAY 1.021277 (6200 2450);
PAINT ORANGE (6200 2450);
DISPLAY INVISIBLE (6200 2450);
FORCEPROP 2 LAST BOM_COST PROC_VRD_PVCCIO_CPU0
J 0
(6200 2450);
DISPLAY 2.340426 (6200 2450);
PAINT WHITE (6200 2450);
DISPLAY INVISIBLE (6200 2450);
FORCEPROP 2 LAST ROOM PVCCIO_CPU0
J 0
(6050 2475);
DISPLAY 3.127660 (6050 2475);
PAINT WHITE (6050 2475);
DISPLAY INVISIBLE (6050 2475);
FORCEPROP 1 LAST OFFPAGE TRUE
J 0
(6775 2275);
PAINT GREEN (6775 2275);
DISPLAY INVISIBLE (6775 2275);
FORCEPROP 1 LAST COMMENT_BODY TRUE
J 0
(6575 2300);
DISPLAY 2.723404 (6575 2300);
PAINT PEACH (6575 2300);
DISPLAY INVISIBLE (6575 2300);
FORCEADD CAP..1
(5850 2850);
FORCEPROP 1 LAST PART_NUMBER C95333-007
J 0
(5900 2700);
DISPLAY 0.617021 (5900 2700);
PAINT BLUE (5900 2700);
FORCEPROP 1 LAST VALUE 10UF
J 0
(5900 2900);
DISPLAY 0.617021 (5900 2900);
PAINT SKYBLUE (5900 2900);
FORCEPROP 1 LAST LOCATION C3L7
J 0
(5900 2950);
DISPLAY 0.617021 (5900 2950);
PAINT AQUA (5900 2950);
FORCEPROP 1 LAST VOLTAGE 16V
J 0
(5900 2850);
DISPLAY 0.617021 (5900 2850);
PAINT SKYBLUE (5900 2850);
FORCEPROP 1 LAST TOLERANCE 10%
J 0
(5900 2800);
DISPLAY 0.617021 (5900 2800);
PAINT SKYBLUE (5900 2800);
FORCEPROP 1 LAST PACK_TYPE 0805
J 0
(5900 2650);
DISPLAY 0.617021 (5900 2650);
PAINT SKYBLUE (5900 2650);
FORCEPROP 1 LAST MATERIAL X6S
J 0
(5900 2750);
DISPLAY 0.617021 (5900 2750);
PAINT SKYBLUE (5900 2750);
FORCEPROP 1 LASTPIN (5850 2950) $PN 1
J 0
(5860 2930);
DISPLAY 0.617021 (5860 2930);
PAINT WHITE (5860 2930);
FORCEPROP 1 LASTPIN (5850 2750) $PN 2
J 0
(5860 2730);
DISPLAY 0.617021 (5860 2730);
PAINT WHITE (5860 2730);
FORCEPROP 2 LAST ROOM P1V05_PCH_STBY_VR
J 0
(5900 3000);
DISPLAY 2.212766 (5900 3000);
PAINT WHITE (5900 3000);
DISPLAY INVISIBLE (5900 3000);
FORCEPROP 2 LAST SEC 1
J 0
(5900 3050);
DISPLAY 1.106383 (5900 3050);
PAINT MONO (5900 3050);
DISPLAY INVISIBLE (5900 3050);
FORCEPROP 2 LAST SEC_TYPE 0805
J 0
(5900 3050);
DISPLAY 1.659574 (5900 3050);
PAINT ORANGE (5900 3050);
DISPLAY INVISIBLE (5900 3050);
FORCEPROP 2 LAST CDS_LOCATION C3L7
J 0
(5900 2950);
DISPLAY 0.617021 (5900 2950);
PAINT AQUA (5900 2950);
DISPLAY INVISIBLE (5900 2950);
FORCEPROP 1 LAST PATH I31
J 0
(5900 3000);
DISPLAY 0.978723 (5900 3000);
PAINT WHITE (5900 3000);
DISPLAY INVISIBLE (5900 3000);
FORCEPROP 2 LAST CDS_LIB mstr_discrete
J 0
(5850 2850);
DISPLAY 1.617021 (5850 2850);
PAINT ORANGE (5850 2850);
DISPLAY INVISIBLE (5850 2850);
FORCEADD CAP..1
(6100 2825);
FORCEPROP 1 LAST PART_NUMBER C95333-007
J 0
(6150 2675);
DISPLAY 0.617021 (6150 2675);
PAINT BLUE (6150 2675);
FORCEPROP 1 LAST LOCATION C3L10
J 0
(6150 2925);
DISPLAY 0.617021 (6150 2925);
PAINT AQUA (6150 2925);
FORCEPROP 1 LAST VOLTAGE 16V
J 0
(6150 2825);
DISPLAY 0.617021 (6150 2825);
PAINT SKYBLUE (6150 2825);
FORCEPROP 1 LAST VALUE 10UF
J 0
(6150 2875);
DISPLAY 0.617021 (6150 2875);
PAINT SKYBLUE (6150 2875);
FORCEPROP 1 LAST TOLERANCE 10%
J 0
(6150 2775);
DISPLAY 0.617021 (6150 2775);
PAINT SKYBLUE (6150 2775);
FORCEPROP 1 LAST PACK_TYPE 0805
J 0
(6150 2625);
DISPLAY 0.617021 (6150 2625);
PAINT SKYBLUE (6150 2625);
FORCEPROP 1 LAST MATERIAL X6S
J 0
(6150 2725);
DISPLAY 0.617021 (6150 2725);
PAINT SKYBLUE (6150 2725);
FORCEPROP 1 LASTPIN (6100 2925) $PN 1
J 0
(6110 2905);
DISPLAY 0.617021 (6110 2905);
PAINT WHITE (6110 2905);
FORCEPROP 1 LASTPIN (6100 2725) $PN 2
J 0
(6110 2705);
DISPLAY 0.617021 (6110 2705);
PAINT WHITE (6110 2705);
FORCEPROP 2 LAST SEC_TYPE 0805
J 0
(6150 3025);
DISPLAY 1.659574 (6150 3025);
PAINT ORANGE (6150 3025);
DISPLAY INVISIBLE (6150 3025);
FORCEPROP 2 LAST SEC 1
J 0
(6150 3025);
DISPLAY 1.106383 (6150 3025);
PAINT MONO (6150 3025);
DISPLAY INVISIBLE (6150 3025);
FORCEPROP 2 LAST CDS_LOCATION C3L10
J 0
(6150 2925);
DISPLAY 0.617021 (6150 2925);
PAINT AQUA (6150 2925);
DISPLAY INVISIBLE (6150 2925);
FORCEPROP 1 LAST PATH I32
J 0
(6150 2975);
DISPLAY 0.978723 (6150 2975);
PAINT WHITE (6150 2975);
DISPLAY INVISIBLE (6150 2975);
FORCEPROP 2 LAST ROOM P1V05_PCH_STBY_VR
J 0
(6150 2975);
DISPLAY 2.212766 (6150 2975);
PAINT WHITE (6150 2975);
DISPLAY INVISIBLE (6150 2975);
FORCEPROP 2 LAST CDS_LIB mstr_discrete
J 0
(6100 2825);
DISPLAY 1.617021 (6100 2825);
PAINT ORANGE (6100 2825);
DISPLAY INVISIBLE (6100 2825);
FORCEADD CAP..1
(6350 2825);
FORCEPROP 1 LAST PART_NUMBER D97712-011
J 0
(6400 2675);
DISPLAY 0.617021 (6400 2675);
PAINT BLUE (6400 2675);
FORCEPROP 1 LAST MATERIAL X6S
J 0
(6400 2725);
DISPLAY 0.617021 (6400 2725);
PAINT SKYBLUE (6400 2725);
FORCEPROP 1 LAST VOLTAGE 16V
J 0
(6400 2825);
DISPLAY 0.617021 (6400 2825);
PAINT SKYBLUE (6400 2825);
FORCEPROP 1 LAST PACK_TYPE 0402
J 0
(6400 2625);
DISPLAY 0.617021 (6400 2625);
PAINT SKYBLUE (6400 2625);
FORCEPROP 1 LAST TOLERANCE 10%
J 0
(6400 2775);
DISPLAY 0.617021 (6400 2775);
PAINT SKYBLUE (6400 2775);
FORCEPROP 1 LAST VALUE 1.0UF
J 0
(6400 2875);
DISPLAY 0.617021 (6400 2875);
PAINT SKYBLUE (6400 2875);
FORCEPROP 1 LAST LOCATION C7A9
J 0
(6400 2925);
DISPLAY 0.617021 (6400 2925);
PAINT AQUA (6400 2925);
FORCEPROP 1 LASTPIN (6350 2925) $PN 1
J 0
(6360 2905);
DISPLAY 0.617021 (6360 2905);
PAINT WHITE (6360 2905);
FORCEPROP 1 LASTPIN (6350 2725) $PN 2
J 0
(6360 2705);
DISPLAY 0.617021 (6360 2705);
PAINT WHITE (6360 2705);
FORCEPROP 2 LAST SEC_TYPE 0402
J 0
(6400 3025);
DISPLAY 1.659574 (6400 3025);
PAINT ORANGE (6400 3025);
DISPLAY INVISIBLE (6400 3025);
FORCEPROP 2 LAST ROOM P1V05_PCH_STBY_VR
J 0
(6400 2975);
DISPLAY 2.212766 (6400 2975);
PAINT WHITE (6400 2975);
DISPLAY INVISIBLE (6400 2975);
FORCEPROP 1 LAST PATH I33
J 0
(6400 2975);
DISPLAY 0.978723 (6400 2975);
PAINT WHITE (6400 2975);
DISPLAY INVISIBLE (6400 2975);
FORCEPROP 2 LAST CDS_LOCATION C7A9
J 0
(6400 2925);
DISPLAY 0.617021 (6400 2925);
PAINT AQUA (6400 2925);
DISPLAY INVISIBLE (6400 2925);
FORCEPROP 2 LAST SEC 1
J 0
(6400 3025);
DISPLAY 1.106383 (6400 3025);
PAINT MONO (6400 3025);
DISPLAY INVISIBLE (6400 3025);
FORCEPROP 2 LAST CDS_LIB mstr_discrete
J 0
(6350 2825);
DISPLAY 1.617021 (6350 2825);
PAINT ORANGE (6350 2825);
DISPLAY INVISIBLE (6350 2825);
FORCEADD CAP..1
R 2
(6900 2075);
FORCEPROP 1 LASTPIN (6900 2175) $PN 1
J 2
(6890 2155);
DISPLAY 0.617021 (6890 2155);
PAINT ORANGE (6890 2155);
FORCEPROP 1 LAST PART_NUMBER A36096-104
J 2
(6850 1925);
DISPLAY 0.617021 (6850 1925);
PAINT BLUE (6850 1925);
FORCEPROP 1 LAST MATERIAL X7R
J 2
(6850 1975);
DISPLAY 0.617021 (6850 1975);
PAINT SKYBLUE (6850 1975);
FORCEPROP 1 LAST TOLERANCE 10%
J 2
(6850 2025);
DISPLAY 0.617021 (6850 2025);
PAINT SKYBLUE (6850 2025);
FORCEPROP 1 LAST VALUE 0.220UF
J 2
(6850 2125);
DISPLAY 0.617021 (6850 2125);
PAINT SKYBLUE (6850 2125);
FORCEPROP 1 LAST LOCATION C7A44
J 2
(6850 2175);
DISPLAY 0.617021 (6850 2175);
PAINT AQUA (6850 2175);
FORCEPROP 1 LAST PACK_TYPE 0402
J 2
(6850 1875);
DISPLAY 0.617021 (6850 1875);
PAINT SKYBLUE (6850 1875);
FORCEPROP 1 LASTPIN (6900 1975) $PN 2
J 2
(6890 1955);
DISPLAY 0.617021 (6890 1955);
PAINT ORANGE (6890 1955);
FORCEPROP 1 LAST VOLTAGE 16V
J 2
(6850 2075);
DISPLAY 0.617021 (6850 2075);
PAINT SKYBLUE (6850 2075);
FORCEPROP 2 LAST SEC_TYPE 0402
J 0
(6850 2275);
DISPLAY 1.021277 (6850 2275);
PAINT ORANGE (6850 2275);
DISPLAY INVISIBLE (6850 2275);
FORCEPROP 0 LAST SPOF TRUE
J 0
(6850 2275);
DISPLAY 1.021277 (6850 2275);
PAINT ORANGE (6850 2275);
DISPLAY INVISIBLE (6850 2275);
FORCEPROP 2 LAST CDS_LIB mstr_discrete
J 0
(6900 2075);
PAINT ORANGE (6900 2075);
DISPLAY INVISIBLE (6900 2075);
FORCEPROP 2 LAST SEC 1
J 0
(6850 2275);
DISPLAY 0.680851 (6850 2275);
PAINT MONO (6850 2275);
DISPLAY INVISIBLE (6850 2275);
FORCEPROP 1 LAST PATH I34
J 2
(6850 2225);
DISPLAY 0.978723 (6850 2225);
PAINT WHITE (6850 2225);
DISPLAY INVISIBLE (6850 2225);
FORCEPROP 2 LAST ROOM P1V05_PCH_STBY_VR
J 0
(6850 2225);
DISPLAY 2.212766 (6850 2225);
PAINT WHITE (6850 2225);
DISPLAY INVISIBLE (6850 2225);
FORCEADD CAP_A..1
(6575 2850);
FORCEPROP 1 LAST PART_NUMBER A36096-030
J 0
(6625 2700);
DISPLAY 0.617021 (6625 2700);
PAINT BLUE (6625 2700);
FORCEPROP 1 LAST PACK_TYPE 0402V
J 0
(6625 2650);
DISPLAY 0.617021 (6625 2650);
PAINT SKYBLUE (6625 2650);
FORCEPROP 1 LAST MATERIAL X7R
J 0
(6625 2750);
DISPLAY 0.617021 (6625 2750);
PAINT SKYBLUE (6625 2750);
FORCEPROP 1 LAST VOLTAGE 16V
J 0
(6625 2850);
DISPLAY 0.617021 (6625 2850);
PAINT SKYBLUE (6625 2850);
FORCEPROP 1 LAST TOLERANCE 10%
J 0
(6625 2800);
DISPLAY 0.617021 (6625 2800);
PAINT SKYBLUE (6625 2800);
FORCEPROP 1 LAST VALUE 0.1UF
J 0
(6625 2900);
DISPLAY 0.617021 (6625 2900);
PAINT SKYBLUE (6625 2900);
FORCEPROP 1 LASTPIN (6575 2950) $PN 1
J 0
(6585 2930);
DISPLAY 0.617021 (6585 2930);
PAINT WHITE (6585 2930);
FORCEPROP 1 LASTPIN (6575 2750) $PN 2
J 0
(6585 2730);
DISPLAY 0.617021 (6585 2730);
PAINT WHITE (6585 2730);
FORCEPROP 1 LAST LOCATION C7A40
J 0
(6625 2950);
DISPLAY 0.617021 (6625 2950);
PAINT AQUA (6625 2950);
FORCEPROP 2 LAST SEC 1
J 0
(6625 3050);
DISPLAY 1.106383 (6625 3050);
PAINT MONO (6625 3050);
DISPLAY INVISIBLE (6625 3050);
FORCEPROP 2 LAST SEC_TYPE 0402V
J 0
(6625 3050);
DISPLAY 1.659574 (6625 3050);
PAINT ORANGE (6625 3050);
DISPLAY INVISIBLE (6625 3050);
FORCEPROP 2 LAST ROOM P1V05_PCH_STBY_VR
J 0
(6625 3000);
DISPLAY 2.212766 (6625 3000);
PAINT WHITE (6625 3000);
DISPLAY INVISIBLE (6625 3000);
FORCEPROP 1 LAST PATH I35
J 0
(6625 3000);
DISPLAY 0.978723 (6625 3000);
PAINT WHITE (6625 3000);
DISPLAY INVISIBLE (6625 3000);
FORCEPROP 2 LAST CDS_SEC 1
J 0
(6625 3000);
PAINT ORANGE (6625 3000);
DISPLAY INVISIBLE (6625 3000);
FORCEPROP 2 LAST CDS_LIB dev_discrete
J 0
(6575 2850);
PAINT ORANGE (6575 2850);
DISPLAY INVISIBLE (6575 2850);
FORCEADD CAP..1
(6850 2850);
FORCEPROP 1 LAST PACK_TYPE 0402
J 0
(6900 2650);
DISPLAY 0.617021 (6900 2650);
PAINT SKYBLUE (6900 2650);
FORCEPROP 1 LAST PART_NUMBER D97712-011
J 0
(6900 2700);
DISPLAY 0.617021 (6900 2700);
PAINT BLUE (6900 2700);
FORCEPROP 1 LAST MATERIAL X6S
J 0
(6900 2750);
DISPLAY 0.617021 (6900 2750);
PAINT SKYBLUE (6900 2750);
FORCEPROP 1 LAST TOLERANCE 10%
J 0
(6900 2800);
DISPLAY 0.617021 (6900 2800);
PAINT SKYBLUE (6900 2800);
FORCEPROP 1 LAST VALUE 1.0UF
J 0
(6900 2900);
DISPLAY 0.617021 (6900 2900);
PAINT SKYBLUE (6900 2900);
FORCEPROP 1 LAST LOCATION C7A10
J 0
(6900 2950);
DISPLAY 0.617021 (6900 2950);
PAINT AQUA (6900 2950);
FORCEPROP 1 LASTPIN (6850 2950) $PN 1
J 0
(6860 2930);
DISPLAY 0.617021 (6860 2930);
PAINT WHITE (6860 2930);
FORCEPROP 1 LASTPIN (6850 2750) $PN 2
J 0
(6860 2730);
DISPLAY 0.617021 (6860 2730);
PAINT WHITE (6860 2730);
FORCEPROP 1 LAST VOLTAGE 16V
J 0
(6900 2850);
DISPLAY 0.617021 (6900 2850);
PAINT SKYBLUE (6900 2850);
FORCEPROP 2 LAST ROOM P1V05_PCH_STBY_VR
J 0
(6900 3000);
DISPLAY 2.212766 (6900 3000);
PAINT WHITE (6900 3000);
DISPLAY INVISIBLE (6900 3000);
FORCEPROP 2 LAST SEC 1
J 0
(6900 3050);
DISPLAY 1.106383 (6900 3050);
PAINT MONO (6900 3050);
DISPLAY INVISIBLE (6900 3050);
FORCEPROP 2 LAST SEC_TYPE 0402
J 0
(6900 3050);
DISPLAY 1.659574 (6900 3050);
PAINT ORANGE (6900 3050);
DISPLAY INVISIBLE (6900 3050);
FORCEPROP 2 LAST CDS_LOCATION C7A10
J 0
(6900 2950);
DISPLAY 0.617021 (6900 2950);
PAINT AQUA (6900 2950);
DISPLAY INVISIBLE (6900 2950);
FORCEPROP 1 LAST PATH I36
J 0
(6900 3000);
DISPLAY 0.978723 (6900 3000);
PAINT WHITE (6900 3000);
DISPLAY INVISIBLE (6900 3000);
FORCEPROP 2 LAST CDS_LIB mstr_discrete
J 0
(6850 2850);
DISPLAY 1.617021 (6850 2850);
PAINT ORANGE (6850 2850);
DISPLAY INVISIBLE (6850 2850);
FORCEADD CAP_A..1
R 2
(7550 2850);
FORCEPROP 1 LASTPIN (7550 2950) $PN 1
J 2
(7540 2930);
DISPLAY 0.617021 (7540 2930);
PAINT WHITE (7540 2930);
FORCEPROP 1 LASTPIN (7550 2750) $PN 2
J 2
(7540 2730);
DISPLAY 0.617021 (7540 2730);
PAINT WHITE (7540 2730);
FORCEPROP 1 LAST VALUE 1.0UF
J 2
(7500 2900);
DISPLAY 0.617021 (7500 2900);
PAINT SKYBLUE (7500 2900);
FORCEPROP 1 LAST TOLERANCE 10%
J 2
(7500 2800);
DISPLAY 0.617021 (7500 2800);
PAINT SKYBLUE (7500 2800);
FORCEPROP 1 LAST LOCATION C3L29
J 2
(7500 2950);
DISPLAY 0.617021 (7500 2950);
PAINT AQUA (7500 2950);
FORCEPROP 1 LAST VOLTAGE 6.3V
J 2
(7500 2850);
DISPLAY 0.617021 (7500 2850);
PAINT SKYBLUE (7500 2850);
FORCEPROP 1 LAST MATERIAL X6S
J 2
(7500 2750);
DISPLAY 0.617021 (7500 2750);
PAINT SKYBLUE (7500 2750);
FORCEPROP 1 LAST PACK_TYPE 0402V
J 2
(7500 2650);
DISPLAY 0.617021 (7500 2650);
PAINT SKYBLUE (7500 2650);
FORCEPROP 1 LAST PART_NUMBER D97712-004
J 2
(7500 2700);
DISPLAY 0.617021 (7500 2700);
PAINT BLUE (7500 2700);
FORCEPROP 2 LAST ROOM P1V05_PCH_STBY_VR
J 0
(7500 3000);
DISPLAY 2.212766 (7500 3000);
PAINT WHITE (7500 3000);
DISPLAY INVISIBLE (7500 3000);
FORCEPROP 2 LAST SEC 1
J 0
(7500 3050);
DISPLAY 1.106383 (7500 3050);
PAINT MONO (7500 3050);
DISPLAY INVISIBLE (7500 3050);
FORCEPROP 2 LAST SEC_TYPE 0402V
J 0
(7500 3050);
DISPLAY 1.659574 (7500 3050);
PAINT ORANGE (7500 3050);
DISPLAY INVISIBLE (7500 3050);
FORCEPROP 1 LAST PATH I38
J 2
(7500 3000);
DISPLAY 0.978723 (7500 3000);
PAINT WHITE (7500 3000);
DISPLAY INVISIBLE (7500 3000);
FORCEPROP 2 LAST CDS_SEC 1
J 0
(7500 3000);
PAINT ORANGE (7500 3000);
DISPLAY INVISIBLE (7500 3000);
FORCEPROP 2 LAST CDS_LIB dev_discrete
J 0
(7550 2850);
PAINT ORANGE (7550 2850);
DISPLAY INVISIBLE (7550 2850);
FORCEADD CAP..1
(7700 2850);
FORCEPROP 1 LAST PART_NUMBER A36096-155
J 0
(7750 2700);
DISPLAY 0.617021 (7750 2700);
PAINT BLUE (7750 2700);
FORCEPROP 1 LAST LOCATION C7A41
J 0
(7750 2950);
DISPLAY 0.617021 (7750 2950);
PAINT AQUA (7750 2950);
FORCEPROP 1 LASTPIN (7700 2950) $PN 1
J 0
(7710 2930);
DISPLAY 0.617021 (7710 2930);
PAINT WHITE (7710 2930);
FORCEPROP 1 LAST VOLTAGE 16V
J 0
(7750 2850);
DISPLAY 0.617021 (7750 2850);
PAINT SKYBLUE (7750 2850);
FORCEPROP 1 LAST VALUE 0.22UF
J 0
(7750 2900);
DISPLAY 0.617021 (7750 2900);
PAINT SKYBLUE (7750 2900);
FORCEPROP 1 LAST TOLERANCE 10%
J 0
(7750 2800);
DISPLAY 0.617021 (7750 2800);
PAINT SKYBLUE (7750 2800);
FORCEPROP 1 LAST MATERIAL X7R
J 0
(7750 2750);
DISPLAY 0.617021 (7750 2750);
PAINT SKYBLUE (7750 2750);
FORCEPROP 1 LAST PACK_TYPE 0402
J 0
(7750 2650);
DISPLAY 0.617021 (7750 2650);
PAINT SKYBLUE (7750 2650);
FORCEPROP 1 LASTPIN (7700 2750) $PN 2
J 0
(7710 2730);
DISPLAY 0.617021 (7710 2730);
PAINT WHITE (7710 2730);
FORCEPROP 2 LAST ROOM P1V05_PCH_STBY_VR
J 0
(7750 3000);
DISPLAY 2.212766 (7750 3000);
PAINT WHITE (7750 3000);
DISPLAY INVISIBLE (7750 3000);
FORCEPROP 2 LAST SEC 1
J 0
(7750 3050);
DISPLAY 1.106383 (7750 3050);
PAINT MONO (7750 3050);
DISPLAY INVISIBLE (7750 3050);
FORCEPROP 2 LAST SEC_TYPE 0402
J 0
(7750 3050);
DISPLAY 1.659574 (7750 3050);
PAINT ORANGE (7750 3050);
DISPLAY INVISIBLE (7750 3050);
FORCEPROP 1 LAST PATH I39
J 0
(7750 3000);
DISPLAY 0.978723 (7750 3000);
PAINT WHITE (7750 3000);
DISPLAY INVISIBLE (7750 3000);
FORCEPROP 2 LAST CDS_LIB mstr_discrete
J 0
(7700 2850);
DISPLAY 1.617021 (7700 2850);
PAINT ORANGE (7700 2850);
DISPLAY INVISIBLE (7700 2850);
FORCEADD RES..1
(7075 3275);
FORCEPROP 1 LASTPIN (6975 3275) $PN 1
J 0
(6987 3287);
DISPLAY 0.617021 (6987 3287);
PAINT WHITE (6987 3287);
FORCEPROP 1 LAST WATTAGE 1/16W
J 2
(7100 3100);
DISPLAY 0.617021 (7100 3100);
PAINT SKYBLUE (7100 3100);
FORCEPROP 1 LAST TOLERANCE 1%
J 0
(7025 3150);
DISPLAY 0.617021 (7025 3150);
PAINT SKYBLUE (7025 3150);
FORCEPROP 1 LAST VALUE 1.0
J 2
(6975 3150);
DISPLAY 0.617021 (6975 3150);
PAINT SKYBLUE (6975 3150);
FORCEPROP 1 LASTPIN (7175 3275) $PN 2
J 0
(7137 3287);
DISPLAY 0.617021 (7137 3287);
PAINT WHITE (7137 3287);
FORCEPROP 1 LAST PACK_TYPE 0402
J 0
(7125 3150);
DISPLAY 0.617021 (7125 3150);
PAINT SKYBLUE (7125 3150);
FORCEPROP 1 LAST LOCATION R3L4
J 0
(7025 3325);
DISPLAY 0.617021 (7025 3325);
PAINT AQUA (7025 3325);
FORCEPROP 1 LAST PART_NUMBER G21796-090
J 0
(6950 3200);
DISPLAY 0.617021 (6950 3200);
PAINT BLUE (6950 3200);
FORCEPROP 1 LAST MATERIAL CHIP
J 0
(7150 3100);
DISPLAY 0.617021 (7150 3100);
PAINT SKYBLUE (7150 3100);
FORCEPROP 2 LAST ROOM P1V05_PCH_STBY_VR
J 0
(7025 3375);
DISPLAY 2.212766 (7025 3375);
PAINT WHITE (7025 3375);
DISPLAY INVISIBLE (7025 3375);
FORCEPROP 1 LAST PATH I41
J 0
(7025 3425);
DISPLAY 0.978723 (7025 3425);
PAINT WHITE (7025 3425);
DISPLAY INVISIBLE (7025 3425);
FORCEPROP 2 LAST SEC 1
J 0
(7025 3475);
DISPLAY 1.106383 (7025 3475);
PAINT MONO (7025 3475);
DISPLAY INVISIBLE (7025 3475);
FORCEPROP 2 LAST SEC_TYPE 0402
J 0
(7025 3475);
DISPLAY 1.659574 (7025 3475);
PAINT ORANGE (7025 3475);
DISPLAY INVISIBLE (7025 3475);
FORCEPROP 2 LAST CDS_LOCATION R3L4
J 0
(7025 3325);
DISPLAY 0.617021 (7025 3325);
PAINT AQUA (7025 3325);
DISPLAY INVISIBLE (7025 3325);
FORCEPROP 2 LAST CDS_LIB mstr_discrete
J 0
(7075 3275);
DISPLAY 1.617021 (7075 3275);
PAINT ORANGE (7075 3275);
DISPLAY INVISIBLE (7075 3275);
FORCEADD P5V_STBY..1
(8375 3400);
FORCEPROP 3 LASTPIN (8375 3350) SIG_NAME P5V_STBY\g
J 0
(8385 3360);
DISPLAY 0.659574 (8385 3360);
PAINT MONO (8385 3360);
DISPLAY INVISIBLE (8385 3360);
FORCEPROP 1 LAST SIZE 1B
J 0
(8420 3422);
DISPLAY 0.340426 (8420 3422);
PAINT GREEN (8420 3422);
DISPLAY INVISIBLE (8420 3422);
FORCEPROP 1 LAST VOLTAGE 5.0V
J 0
(8330 3357);
DISPLAY 0.340426 (8330 3357);
PAINT SKYBLUE (8330 3357);
DISPLAY INVISIBLE (8330 3357);
FORCEPROP 1 LAST PATH I42
J 0
(8420 3402);
DISPLAY 0.340426 (8420 3402);
PAINT GREEN (8420 3402);
DISPLAY INVISIBLE (8420 3402);
FORCEPROP 2 LAST CDS_LIB mstr_symbols
J 0
(8375 3400);
PAINT ORANGE (8375 3400);
DISPLAY INVISIBLE (8375 3400);
FORCEPROP 1 LAST BODY_TYPE PLUMBING
J 0
(8330 3357);
DISPLAY 0.340426 (8330 3357);
PAINT GREEN (8330 3357);
DISPLAY INVISIBLE (8330 3357);
FORCEPROP 1 LAST HDL_POWER P5V_STBY
J 0
(8075 3275);
DISPLAY 0.872340 (8075 3275);
PAINT ORANGE (8075 3275);
DISPLAY INVISIBLE (8075 3275);
FORCEADD GND..1
(10375 1850);
FORCEPROP 3 LASTPIN (10375 1900) SIG_NAME GND\g
J 0
(10385 1910);
DISPLAY 0.659574 (10385 1910);
PAINT MONO (10385 1910);
DISPLAY INVISIBLE (10385 1910);
FORCEPROP 2 LAST CDS_LIB mstr_symbols
J 0
(10375 1850);
DISPLAY 1.617021 (10375 1850);
PAINT ORANGE (10375 1850);
DISPLAY INVISIBLE (10375 1850);
FORCEPROP 1 LAST SIZE 1B
J 0
(10450 1800);
DISPLAY 2.787234 (10450 1800);
PAINT GREEN (10450 1800);
DISPLAY INVISIBLE (10450 1800);
FORCEPROP 1 LAST PATH I44
J 0
(10450 1850);
DISPLAY 0.872340 (10450 1850);
PAINT AQUA (10450 1850);
DISPLAY INVISIBLE (10450 1850);
FORCEPROP 1 LAST VOLTAGE 0.0V
J 0
(10330 1807);
DISPLAY 0.340426 (10330 1807);
PAINT SKYBLUE (10330 1807);
DISPLAY INVISIBLE (10330 1807);
FORCEPROP 2 LAST ROOM PVCCIO_CPU0
J 0
(9825 1925);
DISPLAY 3.127660 (9825 1925);
PAINT WHITE (9825 1925);
DISPLAY INVISIBLE (9825 1925);
FORCEPROP 2 LAST BOM_COST PROC_VRD_PVCCIO_CPU0
J 0
(10000 1925);
DISPLAY 2.340426 (10000 1925);
PAINT WHITE (10000 1925);
DISPLAY INVISIBLE (10000 1925);
FORCEPROP 1 LAST BODY_TYPE PLUMBING
J 0
(10330 1807);
DISPLAY 0.340426 (10330 1807);
PAINT GREEN (10330 1807);
DISPLAY INVISIBLE (10330 1807);
FORCEPROP 1 LAST HDL_POWER GND
J 0
(10375 2000);
DISPLAY 2.787234 (10375 2000);
PAINT GREEN (10375 2000);
DISPLAY INVISIBLE (10375 2000);
FORCEADD INDUCTOR..1
(11200 2250);
FORCEPROP 1 LAST PART_NUMBER D92183-036
J 0
(11100 2350);
DISPLAY 0.617021 (11100 2350);
PAINT BLUE (11100 2350);
FORCEPROP 1 LAST LOCATION L7A4
J 0
(11100 2300);
DISPLAY 0.617021 (11100 2300);
PAINT AQUA (11100 2300);
FORCEPROP 1 LASTPIN (11100 2250) $PN 1
J 0
(11100 2260);
DISPLAY 0.617021 (11100 2260);
PAINT WHITE (11100 2260);
FORCEPROP 1 LAST PACK_TYPE SM
J 0
(11165 2115);
DISPLAY 0.617021 (11165 2115);
PAINT SKYBLUE (11165 2115);
FORCEPROP 1 LASTPIN (11300 2250) $PN 2
J 2
(11310 2260);
DISPLAY 0.617021 (11310 2260);
PAINT WHITE (11310 2260);
FORCEPROP 1 LAST MATERIAL IND
J 0
(11215 2165);
DISPLAY 0.617021 (11215 2165);
PAINT SKYBLUE (11215 2165);
FORCEPROP 1 LAST VALUE 0.3UH
J 2
(11195 2165);
DISPLAY 0.617021 (11195 2165);
PAINT SKYBLUE (11195 2165);
FORCEPROP 1 LAST PATH I45
J 0
(11100 2400);
DISPLAY 0.978723 (11100 2400);
PAINT ORANGE (11100 2400);
DISPLAY INVISIBLE (11100 2400);
FORCEPROP 2 LAST SEC 1
J 0
(11124 2449);
DISPLAY 0.680851 (11124 2449);
PAINT MONO (11124 2449);
DISPLAY INVISIBLE (11124 2449);
FORCEPROP 2 LAST SEC_TYPE SM
J 0
(11124 2449);
DISPLAY 1.021277 (11124 2449);
PAINT ORANGE (11124 2449);
DISPLAY INVISIBLE (11124 2449);
FORCEPROP 2 LAST ROOM P1V05_PCH_STBY_VR
J 0
(11100 2350);
DISPLAY 2.212766 (11100 2350);
PAINT WHITE (11100 2350);
DISPLAY INVISIBLE (11100 2350);
FORCEPROP 2 LAST CDS_LOCATION L7A4
J 0
(11100 2300);
DISPLAY 0.617021 (11100 2300);
PAINT AQUA (11100 2300);
DISPLAY INVISIBLE (11100 2300);
FORCEPROP 2 LAST CDS_LIB mstr_discrete
J 0
(11200 2250);
PAINT ORANGE (11200 2250);
DISPLAY INVISIBLE (11200 2250);
FORCEADD CAP..1
(11500 2025);
FORCEPROP 1 LAST LOCATION C7A42
J 0
(11550 2125);
DISPLAY 0.617021 (11550 2125);
PAINT AQUA (11550 2125);
FORCEPROP 1 LAST VALUE 22UF
J 0
(11550 2075);
DISPLAY 0.617021 (11550 2075);
PAINT SKYBLUE (11550 2075);
FORCEPROP 1 LAST TOLERANCE 20%
J 0
(11550 1975);
DISPLAY 0.617021 (11550 1975);
PAINT SKYBLUE (11550 1975);
FORCEPROP 1 LAST MATERIAL X6S
J 0
(11550 1925);
DISPLAY 0.617021 (11550 1925);
PAINT SKYBLUE (11550 1925);
FORCEPROP 1 LASTPIN (11500 1925) $PN 2
J 0
(11510 1905);
DISPLAY 0.617021 (11510 1905);
PAINT WHITE (11510 1905);
FORCEPROP 1 LAST PART_NUMBER C95333-002
J 0
(11550 1875);
DISPLAY 0.617021 (11550 1875);
PAINT BLUE (11550 1875);
FORCEPROP 1 LASTPIN (11500 2125) $PN 1
J 0
(11510 2105);
DISPLAY 0.617021 (11510 2105);
PAINT WHITE (11510 2105);
FORCEPROP 1 LAST PACK_TYPE 0805LF
J 0
(11550 1825);
DISPLAY 0.617021 (11550 1825);
PAINT SKYBLUE (11550 1825);
FORCEPROP 2 LAST CDS_LOCATION C7A42
J 0
(11550 2125);
DISPLAY 0.617021 (11550 2125);
PAINT AQUA (11550 2125);
DISPLAY INVISIBLE (11550 2125);
FORCEPROP 2 LAST SEC 1
J 0
(11555 2225);
DISPLAY 1.106383 (11555 2225);
PAINT MONO (11555 2225);
DISPLAY INVISIBLE (11555 2225);
FORCEPROP 2 LAST SEC_TYPE 0805LF
J 0
(11555 2225);
DISPLAY 1.659574 (11555 2225);
PAINT ORANGE (11555 2225);
DISPLAY INVISIBLE (11555 2225);
FORCEPROP 2 LAST BOM_COST PROC_VRD_PVCCIO_CPU0
J 0
(11550 2175);
DISPLAY 2.340426 (11550 2175);
PAINT WHITE (11550 2175);
DISPLAY INVISIBLE (11550 2175);
FORCEPROP 2 LAST ROOM P1V05_PCH_STBY_VR
J 0
(11550 2175);
DISPLAY 2.340426 (11550 2175);
PAINT WHITE (11550 2175);
DISPLAY INVISIBLE (11550 2175);
FORCEPROP 1 LAST PATH I46
J 0
(11550 2175);
DISPLAY 0.978723 (11550 2175);
PAINT WHITE (11550 2175);
DISPLAY INVISIBLE (11550 2175);
FORCEPROP 2 LAST CDS_LIB mstr_discrete
J 0
(11500 2025);
DISPLAY 1.617021 (11500 2025);
PAINT ORANGE (11500 2025);
DISPLAY INVISIBLE (11500 2025);
FORCEPROP 1 LAST VOLTAGE 4V
J 0
(11550 2025);
DISPLAY 2.340426 (11550 2025);
PAINT SKYBLUE (11550 2025);
DISPLAY INVISIBLE (11550 2025);
FORCEADD GND..1
(11500 1800);
FORCEPROP 3 LASTPIN (11500 1850) SIG_NAME GND\g
J 0
(11510 1860);
DISPLAY 0.659574 (11510 1860);
PAINT MONO (11510 1860);
DISPLAY INVISIBLE (11510 1860);
FORCEPROP 1 LAST PATH I47
J 0
(11575 1800);
DISPLAY 0.872340 (11575 1800);
PAINT AQUA (11575 1800);
DISPLAY INVISIBLE (11575 1800);
FORCEPROP 1 LAST SIZE 1B
J 0
(11575 1750);
DISPLAY 2.787234 (11575 1750);
PAINT GREEN (11575 1750);
DISPLAY INVISIBLE (11575 1750);
FORCEPROP 2 LAST CDS_LIB mstr_symbols
J 0
(11500 1800);
DISPLAY 1.617021 (11500 1800);
PAINT ORANGE (11500 1800);
DISPLAY INVISIBLE (11500 1800);
FORCEPROP 1 LAST VOLTAGE 0.0V
J 0
(11455 1757);
DISPLAY 0.340426 (11455 1757);
PAINT SKYBLUE (11455 1757);
DISPLAY INVISIBLE (11455 1757);
FORCEPROP 2 LAST BOM_COST PROC_VRD_PVCCIO_CPU0
J 0
(11125 1875);
DISPLAY 2.340426 (11125 1875);
PAINT WHITE (11125 1875);
DISPLAY INVISIBLE (11125 1875);
FORCEPROP 2 LAST ROOM PVCCIO_CPU0
J 0
(10950 1875);
DISPLAY 3.127660 (10950 1875);
PAINT WHITE (10950 1875);
DISPLAY INVISIBLE (10950 1875);
FORCEPROP 1 LAST BODY_TYPE PLUMBING
J 0
(11455 1757);
DISPLAY 0.340426 (11455 1757);
PAINT GREEN (11455 1757);
DISPLAY INVISIBLE (11455 1757);
FORCEPROP 1 LAST HDL_POWER GND
J 0
(11500 1950);
DISPLAY 2.787234 (11500 1950);
PAINT GREEN (11500 1950);
DISPLAY INVISIBLE (11500 1950);
FORCEADD P1V05_PCH_STBY..1
(12550 2350);
FORCEPROP 3 LASTPIN (12550 2300) SIG_NAME P1V05_PCH_STBY\g
J 0
(12560 2310);
DISPLAY 0.659574 (12560 2310);
PAINT MONO (12560 2310);
DISPLAY INVISIBLE (12560 2310);
FORCEPROP 2 LAST ROOM PVCCIO_CPU0
J 0
(12550 2450);
DISPLAY 3.127660 (12550 2450);
PAINT WHITE (12550 2450);
DISPLAY INVISIBLE (12550 2450);
FORCEPROP 1 LAST PATH I48
J 0
(12600 2375);
DISPLAY 0.872340 (12600 2375);
PAINT AQUA (12600 2375);
DISPLAY INVISIBLE (12600 2375);
FORCEPROP 2 LAST BOM_COST PROC_VRD_PVCCIO_CPU0
J 0
(12550 2450);
DISPLAY 2.340426 (12550 2450);
PAINT WHITE (12550 2450);
DISPLAY INVISIBLE (12550 2450);
FORCEPROP 2 LAST CDS_LIB mstr_symbols
J 0
(12550 2350);
PAINT ORANGE (12550 2350);
DISPLAY INVISIBLE (12550 2350);
FORCEPROP 1 LAST VOLTAGE 1.05V
J 0
(12505 2307);
DISPLAY 0.340426 (12505 2307);
PAINT SKYBLUE (12505 2307);
DISPLAY INVISIBLE (12505 2307);
FORCEPROP 1 LAST BODY_TYPE PLUMBING
J 0
(12505 2307);
DISPLAY 0.340426 (12505 2307);
PAINT GREEN (12505 2307);
DISPLAY INVISIBLE (12505 2307);
FORCEPROP 1 LAST HDL_POWER P1V05_PCH_STBY
J 0
(12550 2400);
DISPLAY 0.872340 (12550 2400);
PAINT GREEN (12550 2400);
DISPLAY INVISIBLE (12550 2400);
FORCEADD OFFPAGE..2
(11950 3225);
FORCEPROP 2 LAST $XR0 235 
J 0
(12139 3225);
DISPLAY 0.638298 (12139 3225);
PAINT MONO (12139 3225);
FORCEPROP 2 LAST ROOM PVCCIO_CPU0
J 0
(11550 3300);
DISPLAY 3.127660 (11550 3300);
PAINT WHITE (11550 3300);
DISPLAY INVISIBLE (11550 3300);
FORCEPROP 2 LAST CDS_LIB mstr_standard
J 0
(11950 3225);
DISPLAY 1.617021 (11950 3225);
PAINT ORANGE (11950 3225);
DISPLAY INVISIBLE (11950 3225);
FORCEPROP 2 LAST PATH I52
J 0
(12150 3275);
DISPLAY 1.021277 (12150 3275);
PAINT ORANGE (12150 3275);
DISPLAY INVISIBLE (12150 3275);
FORCEPROP 2 LAST BOM_COST PROC_VRD_PVCCIO_CPU0
J 0
(12150 3275);
DISPLAY 2.340426 (12150 3275);
PAINT WHITE (12150 3275);
DISPLAY INVISIBLE (12150 3275);
FORCEPROP 1 LAST OFFPAGE TRUE
J 0
(12275 3100);
PAINT GREEN (12275 3100);
DISPLAY INVISIBLE (12275 3100);
FORCEPROP 1 LAST COMMENT_BODY TRUE
J 0
(11905 3130);
DISPLAY 2.787234 (11905 3130);
PAINT PEACH (11905 3130);
DISPLAY INVISIBLE (11905 3130);
FORCEADD OFFPAGE..2
(11300 3050);
FORCEPROP 2 LAST $XR0 235 
J 0
(11489 3050);
DISPLAY 0.638298 (11489 3050);
PAINT MONO (11489 3050);
FORCEPROP 2 LAST PATH I53
J 0
(11500 3100);
DISPLAY 1.021277 (11500 3100);
PAINT ORANGE (11500 3100);
DISPLAY INVISIBLE (11500 3100);
FORCEPROP 2 LAST BOM_COST PROC_VRD_PVCCIO_CPU0
J 0
(11500 3100);
DISPLAY 2.340426 (11500 3100);
PAINT WHITE (11500 3100);
DISPLAY INVISIBLE (11500 3100);
FORCEPROP 2 LAST CDS_LIB mstr_standard
J 0
(11300 3050);
DISPLAY 1.617021 (11300 3050);
PAINT ORANGE (11300 3050);
DISPLAY INVISIBLE (11300 3050);
FORCEPROP 2 LAST ROOM PVCCIO_CPU0
J 0
(10900 3125);
DISPLAY 3.127660 (10900 3125);
PAINT WHITE (10900 3125);
DISPLAY INVISIBLE (10900 3125);
FORCEPROP 1 LAST OFFPAGE TRUE
J 0
(11625 2925);
PAINT GREEN (11625 2925);
DISPLAY INVISIBLE (11625 2925);
FORCEPROP 1 LAST COMMENT_BODY TRUE
J 0
(11255 2955);
DISPLAY 2.787234 (11255 2955);
PAINT PEACH (11255 2955);
DISPLAY INVISIBLE (11255 2955);
FORCEADD OFFPAGE..2
(11225 2700);
FORCEPROP 2 LAST $XR0 235 
J 0
(11414 2700);
DISPLAY 0.638298 (11414 2700);
PAINT MONO (11414 2700);
FORCEPROP 1 LAST COMMENT_BODY TRUE
J 0
(11180 2605);
DISPLAY 2.787234 (11180 2605);
PAINT PEACH (11180 2605);
DISPLAY INVISIBLE (11180 2605);
FORCEPROP 1 LAST OFFPAGE TRUE
J 0
(11550 2575);
PAINT GREEN (11550 2575);
DISPLAY INVISIBLE (11550 2575);
FORCEPROP 2 LAST CDS_LIB mstr_standard
J 0
(11225 2700);
DISPLAY 1.617021 (11225 2700);
PAINT ORANGE (11225 2700);
DISPLAY INVISIBLE (11225 2700);
FORCEPROP 2 LAST ROOM PVCCIO_CPU0
J 0
(10825 2775);
DISPLAY 3.127660 (10825 2775);
PAINT WHITE (10825 2775);
DISPLAY INVISIBLE (10825 2775);
FORCEPROP 2 LAST BOM_COST PROC_VRD_PVCCIO_CPU0
J 0
(11425 2750);
DISPLAY 2.340426 (11425 2750);
PAINT WHITE (11425 2750);
DISPLAY INVISIBLE (11425 2750);
FORCEPROP 2 LAST PATH I54
J 0
(11425 2750);
DISPLAY 1.021277 (11425 2750);
PAINT ORANGE (11425 2750);
DISPLAY INVISIBLE (11425 2750);
FORCEADD P1V05_PCH_STBY..1
(7675 1500);
FORCEPROP 3 LASTPIN (7675 1450) SIG_NAME P1V05_PCH_STBY\g
J 0
(7685 1460);
DISPLAY 0.659574 (7685 1460);
PAINT MONO (7685 1460);
DISPLAY INVISIBLE (7685 1460);
FORCEPROP 1 LAST PATH I55
J 0
(7725 1525);
DISPLAY 0.872340 (7725 1525);
PAINT AQUA (7725 1525);
DISPLAY INVISIBLE (7725 1525);
FORCEPROP 2 LAST ROOM PVCCIO_CPU0
J 0
(7675 1600);
DISPLAY 3.127660 (7675 1600);
PAINT WHITE (7675 1600);
DISPLAY INVISIBLE (7675 1600);
FORCEPROP 2 LAST BOM_COST PROC_VRD_PVCCIO_CPU0
J 0
(7675 1600);
DISPLAY 2.340426 (7675 1600);
PAINT WHITE (7675 1600);
DISPLAY INVISIBLE (7675 1600);
FORCEPROP 2 LAST CDS_LIB mstr_symbols
J 0
(7675 1500);
PAINT ORANGE (7675 1500);
DISPLAY INVISIBLE (7675 1500);
FORCEPROP 1 LAST VOLTAGE 1.05V
J 0
(7630 1457);
DISPLAY 0.340426 (7630 1457);
PAINT SKYBLUE (7630 1457);
DISPLAY INVISIBLE (7630 1457);
FORCEPROP 1 LAST BODY_TYPE PLUMBING
J 0
(7630 1457);
DISPLAY 0.340426 (7630 1457);
PAINT GREEN (7630 1457);
DISPLAY INVISIBLE (7630 1457);
FORCEPROP 1 LAST HDL_POWER P1V05_PCH_STBY
J 0
(7675 1550);
DISPLAY 0.872340 (7675 1550);
PAINT GREEN (7675 1550);
DISPLAY INVISIBLE (7675 1550);
FORCEADD RES..1
(7350 1300);
FORCEPROP 1 LAST PART_NUMBER G21497-005
J 0
(7175 1425);
DISPLAY 0.617021 (7175 1425);
PAINT BLUE (7175 1425);
FORCEPROP 1 LAST LOCATION R8B14
J 0
(7150 1475);
DISPLAY 0.617021 (7150 1475);
PAINT AQUA (7150 1475);
FORCEPROP 1 LASTPIN (7450 1300) $PN 2
J 0
(7412 1312);
DISPLAY 0.617021 (7412 1312);
PAINT ORANGE (7412 1312);
FORCEPROP 1 LAST TOLERANCE 5%
J 0
(7300 1350);
DISPLAY 0.617021 (7300 1350);
PAINT SKYBLUE (7300 1350);
FORCEPROP 1 LASTPIN (7250 1300) $PN 1
J 0
(7262 1312);
DISPLAY 0.617021 (7262 1312);
PAINT ORANGE (7262 1312);
FORCEPROP 1 LAST WATTAGE 1/16W
J 2
(7425 1225);
DISPLAY 0.617021 (7425 1225);
PAINT SKYBLUE (7425 1225);
FORCEPROP 1 LAST PACK_TYPE 0402
J 0
(7250 1150);
DISPLAY 0.617021 (7250 1150);
PAINT SKYBLUE (7250 1150);
FORCEPROP 1 LAST VALUE 0.0
J 2
(7225 1350);
DISPLAY 0.617021 (7225 1350);
PAINT SKYBLUE (7225 1350);
FORCEPROP 2 LAST BOM_COST P1V05_PCH_STBY
J 0
(7425 1450);
PAINT MONO (7425 1450);
DISPLAY INVISIBLE (7425 1450);
FORCEPROP 2 LAST ROOM P1V05_PCH_STBY
J 0
(7300 1400);
PAINT ORANGE (7300 1400);
DISPLAY INVISIBLE (7300 1400);
FORCEPROP 1 LAST PATH I56
J 0
(7300 1450);
DISPLAY 0.978723 (7300 1450);
PAINT WHITE (7300 1450);
DISPLAY INVISIBLE (7300 1450);
FORCEPROP 2 LAST CDS_LIB mstr_discrete
J 0
(7350 1300);
PAINT ORANGE (7350 1300);
DISPLAY INVISIBLE (7350 1300);
FORCEPROP 1 LAST MATERIAL CHIP
J 0
(7350 1150);
PAINT SKYBLUE (7350 1150);
DISPLAY INVISIBLE (7350 1150);
FORCEPROP 2 LAST SEC 1
J 0
(7150 1525);
DISPLAY 0.680851 (7150 1525);
PAINT MONO (7150 1525);
DISPLAY INVISIBLE (7150 1525);
FORCEPROP 2 LAST SEC_TYPE 0402
J 0
(7150 1525);
DISPLAY 1.021277 (7150 1525);
PAINT ORANGE (7150 1525);
DISPLAY INVISIBLE (7150 1525);
FORCEPROP 2 LAST CDS_LOCATION R8B14
J 0
(7150 1475);
DISPLAY 0.617021 (7150 1475);
PAINT AQUA (7150 1475);
DISPLAY INVISIBLE (7150 1475);
FORCEADD RES..2
(7000 1050);
FORCEPROP 1 LAST WATTAGE 1/16W
J 0
(7040 1025);
DISPLAY 0.617021 (7040 1025);
PAINT SKYBLUE (7040 1025);
FORCEPROP 1 LAST VALUE 100.0
J 0
(7045 1125);
DISPLAY 0.617021 (7045 1125);
PAINT SKYBLUE (7045 1125);
FORCEPROP 1 LAST PART_NUMBER G21796-017
J 0
(7040 925);
DISPLAY 0.617021 (7040 925);
PAINT BLUE (7040 925);
FORCEPROP 1 LAST LOCATION R8B15
J 0
(7045 1175);
DISPLAY 0.617021 (7045 1175);
PAINT AQUA (7045 1175);
FORCEPROP 1 LAST MATERIAL EMPTY
J 0
(7040 975);
DISPLAY 0.617021 (7040 975);
PAINT RED (7040 975);
FORCEPROP 1 LAST TOLERANCE 1%
J 0
(7045 1075);
DISPLAY 0.617021 (7045 1075);
PAINT SKYBLUE (7045 1075);
FORCEPROP 1 LASTPIN (7000 1150) $PN 1
J 0
(7005 1112);
DISPLAY 0.617021 (7005 1112);
PAINT ORANGE (7005 1112);
FORCEPROP 1 LAST PACK_TYPE 0402
J 0
(7040 875);
DISPLAY 0.617021 (7040 875);
PAINT SKYBLUE (7040 875);
FORCEPROP 1 LASTPIN (7000 950) $PN 2
J 0
(7005 960);
DISPLAY 0.617021 (7005 960);
PAINT ORANGE (7005 960);
FORCEPROP 0 LAST BOM_COST P1V05_PCH_STBY
J 0
(7050 1375);
DISPLAY 1.021277 (7050 1375);
PAINT ORANGE (7050 1375);
DISPLAY INVISIBLE (7050 1375);
FORCEPROP 0 LAST ROOM P1V05_PCH_STBY
J 0
(7050 1275);
DISPLAY 1.021277 (7050 1275);
PAINT ORANGE (7050 1275);
DISPLAY INVISIBLE (7050 1275);
FORCEPROP 2 LAST NO_XNET_CONNECTION 1
J 0
(7050 1275);
PAINT MONO (7050 1275);
DISPLAY INVISIBLE (7050 1275);
FORCEPROP 2 LAST SEC 1
J 0
(7050 1275);
DISPLAY 0.680851 (7050 1275);
PAINT MONO (7050 1275);
DISPLAY INVISIBLE (7050 1275);
FORCEPROP 2 LAST SEC_TYPE 0402
J 0
(7050 1275);
DISPLAY 1.021277 (7050 1275);
PAINT ORANGE (7050 1275);
DISPLAY INVISIBLE (7050 1275);
FORCEPROP 1 LAST PATH I57
J 0
(7050 1225);
DISPLAY 0.978723 (7050 1225);
PAINT WHITE (7050 1225);
DISPLAY INVISIBLE (7050 1225);
FORCEPROP 2 LAST CDS_LOCATION R8B15
J 0
(7045 1175);
DISPLAY 0.617021 (7045 1175);
PAINT AQUA (7045 1175);
DISPLAY INVISIBLE (7045 1175);
FORCEPROP 2 LAST CDS_LIB mstr_discrete
J 0
(7000 1050);
PAINT ORANGE (7000 1050);
DISPLAY INVISIBLE (7000 1050);
FORCEADD GND..1
(7650 625);
FORCEPROP 3 LASTPIN (7650 675) SIG_NAME GND\g
J 0
(7660 685);
DISPLAY 0.659574 (7660 685);
PAINT MONO (7660 685);
DISPLAY INVISIBLE (7660 685);
FORCEPROP 1 LAST PATH I58
J 0
(7725 625);
DISPLAY 0.872340 (7725 625);
PAINT AQUA (7725 625);
DISPLAY INVISIBLE (7725 625);
FORCEPROP 1 LAST SIZE 1B
J 0
(7725 575);
DISPLAY 0.893617 (7725 575);
PAINT GREEN (7725 575);
DISPLAY INVISIBLE (7725 575);
FORCEPROP 1 LAST VOLTAGE 0
J 0
(7650 625);
PAINT SKYBLUE (7650 625);
DISPLAY INVISIBLE (7650 625);
FORCEPROP 2 LAST CDS_LIB mstr_symbols
J 0
(7650 625);
PAINT ORANGE (7650 625);
DISPLAY INVISIBLE (7650 625);
FORCEPROP 2 LAST BOM_COST MEM_VRD_PVPP_AB
J 0
(7325 700);
PAINT MONO (7325 700);
DISPLAY INVISIBLE (7325 700);
FORCEPROP 2 LAST ROOM VCCP_CPU0_VR
J 0
(7100 700);
PAINT ORANGE (7100 700);
DISPLAY INVISIBLE (7100 700);
FORCEPROP 1 LAST BODY_TYPE PLUMBING
J 0
(7605 582);
DISPLAY 0.340426 (7605 582);
PAINT GREEN (7605 582);
DISPLAY INVISIBLE (7605 582);
FORCEPROP 1 LAST HDL_POWER GND
J 0
(7650 775);
DISPLAY 0.893617 (7650 775);
PAINT GREEN (7650 775);
DISPLAY INVISIBLE (7650 775);
FORCEADD RES..1
(7325 850);
FORCEPROP 1 LAST PART_NUMBER G21497-005
J 0
(7400 950);
DISPLAY 0.617021 (7400 950);
PAINT BLUE (7400 950);
FORCEPROP 1 LAST LOCATION R8B12
J 0
(7400 900);
DISPLAY 0.617021 (7400 900);
PAINT AQUA (7400 900);
FORCEPROP 1 LASTPIN (7425 850) $PN 2
J 0
(7387 862);
DISPLAY 0.617021 (7387 862);
PAINT ORANGE (7387 862);
FORCEPROP 1 LAST TOLERANCE 5%
J 0
(7325 775);
DISPLAY 0.617021 (7325 775);
PAINT SKYBLUE (7325 775);
FORCEPROP 1 LASTPIN (7225 850) $PN 1
J 0
(7237 862);
DISPLAY 0.617021 (7237 862);
PAINT ORANGE (7237 862);
FORCEPROP 1 LAST PACK_TYPE 0402
J 0
(7200 650);
DISPLAY 0.617021 (7200 650);
PAINT SKYBLUE (7200 650);
FORCEPROP 1 LAST WATTAGE 1/16W
J 2
(7300 700);
DISPLAY 0.617021 (7300 700);
PAINT SKYBLUE (7300 700);
FORCEPROP 1 LAST VALUE 0.0
J 2
(7300 775);
DISPLAY 0.617021 (7300 775);
PAINT SKYBLUE (7300 775);
FORCEPROP 2 LAST SEC_TYPE 0402
J 0
(7275 1050);
DISPLAY 1.021277 (7275 1050);
PAINT ORANGE (7275 1050);
DISPLAY INVISIBLE (7275 1050);
FORCEPROP 2 LAST SEC 1
J 0
(7275 1050);
DISPLAY 0.680851 (7275 1050);
PAINT MONO (7275 1050);
DISPLAY INVISIBLE (7275 1050);
FORCEPROP 1 LAST PATH I59
J 0
(7275 1000);
DISPLAY 0.978723 (7275 1000);
PAINT WHITE (7275 1000);
DISPLAY INVISIBLE (7275 1000);
FORCEPROP 2 LAST BOM_COST P1V05_PCH_STBY
J 0
(7400 1000);
PAINT MONO (7400 1000);
DISPLAY INVISIBLE (7400 1000);
FORCEPROP 2 LAST CDS_LIB mstr_discrete
J 0
(7325 850);
PAINT ORANGE (7325 850);
DISPLAY INVISIBLE (7325 850);
FORCEPROP 2 LAST CDS_LOCATION R8B12
J 0
(7400 900);
DISPLAY 0.617021 (7400 900);
PAINT AQUA (7400 900);
DISPLAY INVISIBLE (7400 900);
FORCEPROP 2 LAST ROOM P1V05_PCH_STBY
J 0
(7275 950);
PAINT ORANGE (7275 950);
DISPLAY INVISIBLE (7275 950);
FORCEPROP 1 LAST MATERIAL CHIP
J 0
(7325 700);
PAINT SKYBLUE (7325 700);
DISPLAY INVISIBLE (7325 700);
FORCEADD OFFPAGE..1
(5750 1275);
FORCEPROP 2 LAST $XR0 235 
J 0
(5498 1275);
DISPLAY 0.638298 (5498 1275);
PAINT MONO (5498 1275);
FORCEPROP 2 LAST PATH I60
J 0
(5800 1350);
DISPLAY 1.021277 (5800 1350);
PAINT ORANGE (5800 1350);
DISPLAY INVISIBLE (5800 1350);
FORCEPROP 2 LAST CDS_LIB mstr_standard
J 0
(5750 1275);
PAINT ORANGE (5750 1275);
DISPLAY INVISIBLE (5750 1275);
FORCEPROP 1 LAST OFFPAGE TRUE
J 0
(6075 1150);
DISPLAY 1.170213 (6075 1150);
PAINT GREEN (6075 1150);
DISPLAY INVISIBLE (6075 1150);
FORCEPROP 1 LAST COMMENT_BODY TRUE
J 0
(5875 1175);
DISPLAY 1.170213 (5875 1175);
PAINT GREEN (5875 1175);
DISPLAY INVISIBLE (5875 1175);
FORCEADD OFFPAGE..1
(5750 925);
FORCEPROP 2 LAST $XR0 235 
J 0
(5498 925);
DISPLAY 0.638298 (5498 925);
PAINT MONO (5498 925);
FORCEPROP 2 LAST PATH I61
J 0
(5800 1000);
DISPLAY 1.021277 (5800 1000);
PAINT ORANGE (5800 1000);
DISPLAY INVISIBLE (5800 1000);
FORCEPROP 2 LAST CDS_LIB mstr_standard
J 0
(5750 925);
PAINT ORANGE (5750 925);
DISPLAY INVISIBLE (5750 925);
FORCEPROP 2 LAST BOM_COST MEM_VRD_PVPP_AB
J 0
(5475 975);
PAINT MONO (5475 975);
DISPLAY INVISIBLE (5475 975);
FORCEPROP 1 LAST OFFPAGE TRUE
J 0
(6075 800);
DISPLAY 0.893617 (6075 800);
PAINT GREEN (6075 800);
DISPLAY INVISIBLE (6075 800);
FORCEPROP 1 LAST COMMENT_BODY TRUE
J 0
(5875 825);
DISPLAY 0.893617 (5875 825);
PAINT GREEN (5875 825);
DISPLAY INVISIBLE (5875 825);
FORCEADD CAP..1
R 2
(12350 1225);
FORCEPROP 1 LAST MATERIAL X5R
J 2
(12300 1125);
DISPLAY 0.617021 (12300 1125);
PAINT SKYBLUE (12300 1125);
FORCEPROP 1 LAST VOLTAGE 16V
J 2
(12300 1225);
DISPLAY 0.617021 (12300 1225);
PAINT SKYBLUE (12300 1225);
FORCEPROP 1 LAST PACK_TYPE 1210
J 2
(12325 1075);
DISPLAY 0.617021 (12325 1075);
PAINT SKYBLUE (12325 1075);
FORCEPROP 1 LAST TOLERANCE 20%
J 2
(12300 1175);
DISPLAY 0.617021 (12300 1175);
PAINT SKYBLUE (12300 1175);
FORCEPROP 1 LAST VALUE 100UF
J 2
(12300 1275);
DISPLAY 0.617021 (12300 1275);
PAINT SKYBLUE (12300 1275);
FORCEPROP 1 LAST PART_NUMBER 644066-127
J 2
(12329 1029);
DISPLAY 0.617021 (12329 1029);
PAINT BLUE (12329 1029);
FORCEPROP 1 LAST LOCATION C7A13
J 2
(12300 1325);
DISPLAY 0.617021 (12300 1325);
PAINT AQUA (12300 1325);
FORCEPROP 1 LASTPIN (12350 1325) $PN 1
J 2
(12340 1305);
DISPLAY 0.787234 (12340 1305);
PAINT ORANGE (12340 1305);
DISPLAY INVISIBLE (12340 1305);
FORCEPROP 2 LAST ROOM PVNN_PCH_STBY
J 0
(12300 1375);
DISPLAY 0.723404 (12300 1375);
PAINT ORANGE (12300 1375);
DISPLAY INVISIBLE (12300 1375);
FORCEPROP 1 LAST PATH I63
J 2
(12300 1375);
DISPLAY 0.978723 (12300 1375);
PAINT WHITE (12300 1375);
DISPLAY INVISIBLE (12300 1375);
FORCEPROP 2 LAST CDS_LOCATION C7A13
J 2
(12300 1325);
DISPLAY 0.617021 (12300 1325);
PAINT AQUA (12300 1325);
DISPLAY INVISIBLE (12300 1325);
FORCEPROP 2 LAST $SEC 1
J 0
(12300 1425);
PAINT MONO (12300 1425);
DISPLAY INVISIBLE (12300 1425);
FORCEPROP 2 LAST CDS_SEC 1
J 0
(12300 1425);
PAINT MONO (12300 1425);
DISPLAY INVISIBLE (12300 1425);
FORCEPROP 2 LAST BOM_COST PVNN_PCH_STBY
J 0
(12300 1375);
DISPLAY 0.723404 (12300 1375);
PAINT ORANGE (12300 1375);
DISPLAY INVISIBLE (12300 1375);
FORCEPROP 1 LASTPIN (12350 1125) $PN 2
J 2
(12340 1105);
DISPLAY 0.787234 (12340 1105);
PAINT ORANGE (12340 1105);
DISPLAY INVISIBLE (12340 1105);
FORCEPROP 2 LAST CDS_LIB mstr_discrete
J 0
(12350 1225);
PAINT ORANGE (12350 1225);
DISPLAY INVISIBLE (12350 1225);
FORCEADD GND..1
(12350 925);
FORCEPROP 3 LASTPIN (12350 975) SIG_NAME GND\g
J 0
(12360 985);
DISPLAY 0.659574 (12360 985);
PAINT MONO (12360 985);
DISPLAY INVISIBLE (12360 985);
FORCEPROP 1 LAST PATH I64
J 0
(12425 925);
DISPLAY 0.872340 (12425 925);
PAINT AQUA (12425 925);
DISPLAY INVISIBLE (12425 925);
FORCEPROP 1 LAST SIZE 1B
J 0
(12425 875);
DISPLAY 0.553191 (12425 875);
PAINT ORANGE (12425 875);
DISPLAY INVISIBLE (12425 875);
FORCEPROP 1 LAST VOLTAGE 0.0V
J 0
(12305 882);
DISPLAY 0.340426 (12305 882);
PAINT SKYBLUE (12305 882);
DISPLAY INVISIBLE (12305 882);
FORCEPROP 2 LAST CDS_LIB mstr_symbols
J 0
(12350 925);
PAINT ORANGE (12350 925);
DISPLAY INVISIBLE (12350 925);
FORCEPROP 2 LAST ROOM PVCCIO_CPU1
J 0
(12050 1000);
DISPLAY 0.723404 (12050 1000);
PAINT ORANGE (12050 1000);
DISPLAY INVISIBLE (12050 1000);
FORCEPROP 2 LAST BOM_COST MEM_VRD_PVCCIO_CPU1
J 0
(12000 1000);
DISPLAY 0.617021 (12000 1000);
PAINT ORANGE (12000 1000);
DISPLAY INVISIBLE (12000 1000);
FORCEPROP 1 LAST BODY_TYPE PLUMBING
J 0
(12305 882);
DISPLAY 0.340426 (12305 882);
PAINT GREEN (12305 882);
DISPLAY INVISIBLE (12305 882);
FORCEPROP 1 LAST HDL_POWER GND
J 0
(12350 1075);
DISPLAY 0.553191 (12350 1075);
PAINT GREEN (12350 1075);
DISPLAY INVISIBLE (12350 1075);
FORCEADD CAP..1
R 2
(11975 1250);
FORCEPROP 1 LAST VALUE 100UF
J 2
(11925 1300);
DISPLAY 0.617021 (11925 1300);
PAINT SKYBLUE (11925 1300);
FORCEPROP 1 LAST VOLTAGE 16V
J 2
(11925 1250);
DISPLAY 0.617021 (11925 1250);
PAINT SKYBLUE (11925 1250);
FORCEPROP 1 LAST PACK_TYPE 1210
J 2
(11950 1100);
DISPLAY 0.617021 (11950 1100);
PAINT SKYBLUE (11950 1100);
FORCEPROP 1 LAST TOLERANCE 20%
J 2
(11925 1200);
DISPLAY 0.617021 (11925 1200);
PAINT SKYBLUE (11925 1200);
FORCEPROP 1 LAST MATERIAL X5R
J 2
(11925 1150);
DISPLAY 0.617021 (11925 1150);
PAINT SKYBLUE (11925 1150);
FORCEPROP 1 LAST PART_NUMBER 644066-127
J 2
(11954 1054);
DISPLAY 0.617021 (11954 1054);
PAINT BLUE (11954 1054);
FORCEPROP 1 LAST LOCATION C7A14
J 2
(11925 1350);
DISPLAY 0.617021 (11925 1350);
PAINT AQUA (11925 1350);
FORCEPROP 1 LASTPIN (11975 1350) $PN 1
J 2
(11965 1330);
DISPLAY 0.787234 (11965 1330);
PAINT ORANGE (11965 1330);
DISPLAY INVISIBLE (11965 1330);
FORCEPROP 2 LAST ROOM PVNN_PCH_STBY
J 0
(11925 1400);
DISPLAY 0.723404 (11925 1400);
PAINT ORANGE (11925 1400);
DISPLAY INVISIBLE (11925 1400);
FORCEPROP 1 LAST PATH I65
J 2
(11925 1400);
DISPLAY 0.978723 (11925 1400);
PAINT WHITE (11925 1400);
DISPLAY INVISIBLE (11925 1400);
FORCEPROP 2 LAST CDS_LOCATION C7A14
J 2
(11925 1350);
DISPLAY 0.617021 (11925 1350);
PAINT AQUA (11925 1350);
DISPLAY INVISIBLE (11925 1350);
FORCEPROP 2 LAST $SEC 1
J 0
(11925 1450);
PAINT MONO (11925 1450);
DISPLAY INVISIBLE (11925 1450);
FORCEPROP 2 LAST CDS_SEC 1
J 0
(11925 1450);
PAINT MONO (11925 1450);
DISPLAY INVISIBLE (11925 1450);
FORCEPROP 2 LAST BOM_COST PVNN_PCH_STBY
J 0
(11925 1400);
DISPLAY 0.723404 (11925 1400);
PAINT ORANGE (11925 1400);
DISPLAY INVISIBLE (11925 1400);
FORCEPROP 2 LAST CDS_LIB mstr_discrete
J 0
(11975 1250);
PAINT ORANGE (11975 1250);
DISPLAY INVISIBLE (11975 1250);
FORCEPROP 1 LASTPIN (11975 1150) $PN 2
J 2
(11965 1130);
DISPLAY 0.787234 (11965 1130);
PAINT ORANGE (11965 1130);
DISPLAY INVISIBLE (11965 1130);
FORCEADD GND..1
(11975 925);
FORCEPROP 3 LASTPIN (11975 975) SIG_NAME GND\g
J 0
(11985 985);
DISPLAY 0.659574 (11985 985);
PAINT MONO (11985 985);
DISPLAY INVISIBLE (11985 985);
FORCEPROP 2 LAST ROOM PVCCIO_CPU1
J 0
(11675 1000);
DISPLAY 0.723404 (11675 1000);
PAINT ORANGE (11675 1000);
DISPLAY INVISIBLE (11675 1000);
FORCEPROP 2 LAST BOM_COST MEM_VRD_PVCCIO_CPU1
J 0
(11625 1000);
DISPLAY 0.617021 (11625 1000);
PAINT ORANGE (11625 1000);
DISPLAY INVISIBLE (11625 1000);
FORCEPROP 1 LAST PATH I66
J 0
(12050 925);
DISPLAY 0.872340 (12050 925);
PAINT AQUA (12050 925);
DISPLAY INVISIBLE (12050 925);
FORCEPROP 1 LAST VOLTAGE 0.0V
J 0
(11930 882);
DISPLAY 0.340426 (11930 882);
PAINT SKYBLUE (11930 882);
DISPLAY INVISIBLE (11930 882);
FORCEPROP 1 LAST SIZE 1B
J 0
(12050 875);
DISPLAY 0.553191 (12050 875);
PAINT ORANGE (12050 875);
DISPLAY INVISIBLE (12050 875);
FORCEPROP 2 LAST CDS_LIB mstr_symbols
J 0
(11975 925);
PAINT ORANGE (11975 925);
DISPLAY INVISIBLE (11975 925);
FORCEPROP 1 LAST BODY_TYPE PLUMBING
J 0
(11930 882);
DISPLAY 0.340426 (11930 882);
PAINT GREEN (11930 882);
DISPLAY INVISIBLE (11930 882);
FORCEPROP 1 LAST HDL_POWER GND
J 0
(11975 1075);
DISPLAY 0.553191 (11975 1075);
PAINT GREEN (11975 1075);
DISPLAY INVISIBLE (11975 1075);
FORCEADD PVNN_PCH_STBY..1
(12700 4075);
FORCEPROP 3 LASTPIN (12700 4025) SIG_NAME PVNN_PCH_STBY\g
J 0
(12710 4035);
DISPLAY 0.659574 (12710 4035);
PAINT MONO (12710 4035);
DISPLAY INVISIBLE (12710 4035);
FORCEPROP 2 LAST ROOM PVCCIO_CPU0
J 0
(12700 4175);
DISPLAY 3.127660 (12700 4175);
PAINT WHITE (12700 4175);
DISPLAY INVISIBLE (12700 4175);
FORCEPROP 1 LAST PATH I7
J 0
(12750 4100);
DISPLAY 0.872340 (12750 4100);
PAINT AQUA (12750 4100);
DISPLAY INVISIBLE (12750 4100);
FORCEPROP 2 LAST BOM_COST PROC_VRD_PVCCIO_CPU0
J 0
(12700 4175);
DISPLAY 2.340426 (12700 4175);
PAINT WHITE (12700 4175);
DISPLAY INVISIBLE (12700 4175);
FORCEPROP 2 LAST CDS_LIB mstr_symbols
J 0
(12700 4075);
PAINT ORANGE (12700 4075);
DISPLAY INVISIBLE (12700 4075);
FORCEPROP 1 LAST VOLTAGE 1.0V
J 0
(12655 4032);
DISPLAY 0.340426 (12655 4032);
PAINT SKYBLUE (12655 4032);
DISPLAY INVISIBLE (12655 4032);
FORCEPROP 1 LAST BODY_TYPE PLUMBING
J 0
(12655 4032);
DISPLAY 0.340426 (12655 4032);
PAINT GREEN (12655 4032);
DISPLAY INVISIBLE (12655 4032);
FORCEPROP 1 LAST HDL_POWER PVNN_PCH_STBY
J 1
(12700 4125);
DISPLAY 0.872340 (12700 4125);
PAINT GREEN (12700 4125);
DISPLAY INVISIBLE (12700 4125);
FORCEADD CAPP..1
(11875 3750);
FORCEPROP 1 LAST MATERIAL ALUM
J 0
(11925 3650);
DISPLAY 0.617021 (11925 3650);
PAINT SKYBLUE (11925 3650);
FORCEPROP 1 LASTPIN (11875 3850) $PN 1
J 0
(11885 3835);
DISPLAY 0.617021 (11885 3835);
PAINT ORANGE (11885 3835);
FORCEPROP 1 LAST VOLTAGE 2V
J 0
(11925 3700);
DISPLAY 0.617021 (11925 3700);
PAINT SKYBLUE (11925 3700);
FORCEPROP 1 LAST PACK_TYPE SM
J 0
(11925 3600);
DISPLAY 0.617021 (11925 3600);
PAINT SKYBLUE (11925 3600);
FORCEPROP 1 LAST TOLERANCE 20%
J 0
(11925 3750);
DISPLAY 0.617021 (11925 3750);
PAINT SKYBLUE (11925 3750);
FORCEPROP 1 LASTPIN (11875 3650) $PN 2
J 0
(11885 3635);
DISPLAY 0.617021 (11885 3635);
PAINT ORANGE (11885 3635);
FORCEPROP 1 LAST PART_NUMBER 699013-031
J 0
(11925 3550);
DISPLAY 0.617021 (11925 3550);
PAINT BLUE (11925 3550);
FORCEPROP 1 LAST LOCATION C3L18
J 0
(11925 3850);
DISPLAY 0.617021 (11925 3850);
PAINT AQUA (11925 3850);
FORCEPROP 1 LAST VALUE 470UF
J 0
(11925 3800);
DISPLAY 0.617021 (11925 3800);
PAINT SKYBLUE (11925 3800);
FORCEPROP 0 LAST ROOM PVNN_PCH_STBY
J 0
(11925 3950);
DISPLAY 1.021277 (11925 3950);
PAINT ORANGE (11925 3950);
DISPLAY INVISIBLE (11925 3950);
FORCEPROP 1 LAST PATH I71
J 0
(11925 3900);
DISPLAY 0.978723 (11925 3900);
PAINT ORANGE (11925 3900);
DISPLAY INVISIBLE (11925 3900);
FORCEPROP 2 LAST CDS_LOCATION C3L18
J 0
(11925 3850);
DISPLAY 0.617021 (11925 3850);
PAINT AQUA (11925 3850);
DISPLAY INVISIBLE (11925 3850);
FORCEPROP 2 LAST SEC 1
J 0
(11925 3950);
DISPLAY 0.680851 (11925 3950);
PAINT MONO (11925 3950);
DISPLAY INVISIBLE (11925 3950);
FORCEPROP 2 LAST SEC_TYPE SM
J 0
(11925 3950);
DISPLAY 1.021277 (11925 3950);
PAINT ORANGE (11925 3950);
DISPLAY INVISIBLE (11925 3950);
FORCEPROP 2 LAST CDS_LIB mstr_discrete
J 0
(11875 3750);
PAINT ORANGE (11875 3750);
DISPLAY INVISIBLE (11875 3750);
FORCEADD CAPP..1
(12175 3750);
FORCEPROP 1 LAST TOLERANCE 20%
J 0
(12225 3750);
DISPLAY 0.617021 (12225 3750);
PAINT SKYBLUE (12225 3750);
FORCEPROP 1 LAST VALUE 470UF
J 0
(12225 3800);
DISPLAY 0.617021 (12225 3800);
PAINT SKYBLUE (12225 3800);
FORCEPROP 1 LAST LOCATION C3L20
J 0
(12225 3850);
DISPLAY 0.617021 (12225 3850);
PAINT AQUA (12225 3850);
FORCEPROP 1 LASTPIN (12175 3850) $PN 1
J 0
(12185 3835);
DISPLAY 0.617021 (12185 3835);
PAINT ORANGE (12185 3835);
FORCEPROP 1 LAST VOLTAGE 2V
J 0
(12225 3700);
DISPLAY 0.617021 (12225 3700);
PAINT SKYBLUE (12225 3700);
FORCEPROP 1 LASTPIN (12175 3650) $PN 2
J 0
(12185 3635);
DISPLAY 0.617021 (12185 3635);
PAINT ORANGE (12185 3635);
FORCEPROP 1 LAST MATERIAL ALUM
J 0
(12225 3650);
DISPLAY 0.617021 (12225 3650);
PAINT SKYBLUE (12225 3650);
FORCEPROP 1 LAST PACK_TYPE SM
J 0
(12225 3600);
DISPLAY 0.617021 (12225 3600);
PAINT SKYBLUE (12225 3600);
FORCEPROP 1 LAST PART_NUMBER 699013-031
J 0
(12225 3550);
DISPLAY 0.617021 (12225 3550);
PAINT BLUE (12225 3550);
FORCEPROP 0 LAST ROOM PVNN_PCH_STBY
J 0
(12225 3950);
DISPLAY 1.021277 (12225 3950);
PAINT ORANGE (12225 3950);
DISPLAY INVISIBLE (12225 3950);
FORCEPROP 1 LAST PATH I73
J 0
(12225 3900);
DISPLAY 0.978723 (12225 3900);
PAINT ORANGE (12225 3900);
DISPLAY INVISIBLE (12225 3900);
FORCEPROP 2 LAST CDS_LOCATION C3L20
J 0
(12225 3850);
DISPLAY 0.617021 (12225 3850);
PAINT AQUA (12225 3850);
DISPLAY INVISIBLE (12225 3850);
FORCEPROP 2 LAST SEC 1
J 0
(12225 3950);
DISPLAY 0.680851 (12225 3950);
PAINT MONO (12225 3950);
DISPLAY INVISIBLE (12225 3950);
FORCEPROP 2 LAST SEC_TYPE SM
J 0
(12225 3950);
DISPLAY 1.021277 (12225 3950);
PAINT ORANGE (12225 3950);
DISPLAY INVISIBLE (12225 3950);
FORCEPROP 2 LAST CDS_LIB mstr_discrete
J 0
(12175 3750);
PAINT ORANGE (12175 3750);
DISPLAY INVISIBLE (12175 3750);
FORCEADD CAPP..1
(12450 3750);
FORCEPROP 1 LAST MATERIAL ALUM
J 0
(12500 3650);
DISPLAY 0.617021 (12500 3650);
PAINT SKYBLUE (12500 3650);
FORCEPROP 1 LAST VOLTAGE 2V
J 0
(12500 3700);
DISPLAY 0.617021 (12500 3700);
PAINT SKYBLUE (12500 3700);
FORCEPROP 1 LAST PACK_TYPE SM
J 0
(12500 3600);
DISPLAY 0.617021 (12500 3600);
PAINT SKYBLUE (12500 3600);
FORCEPROP 1 LAST TOLERANCE 20%
J 0
(12500 3750);
DISPLAY 0.617021 (12500 3750);
PAINT SKYBLUE (12500 3750);
FORCEPROP 1 LAST VALUE 470UF
J 0
(12500 3800);
DISPLAY 0.617021 (12500 3800);
PAINT SKYBLUE (12500 3800);
FORCEPROP 1 LAST LOCATION C3L21
J 0
(12500 3850);
DISPLAY 0.617021 (12500 3850);
PAINT AQUA (12500 3850);
FORCEPROP 1 LASTPIN (12450 3850) $PN 1
J 0
(12460 3835);
DISPLAY 0.617021 (12460 3835);
PAINT ORANGE (12460 3835);
FORCEPROP 1 LASTPIN (12450 3650) $PN 2
J 0
(12460 3635);
DISPLAY 0.617021 (12460 3635);
PAINT ORANGE (12460 3635);
FORCEPROP 1 LAST PART_NUMBER 699013-031
J 0
(12500 3550);
DISPLAY 0.617021 (12500 3550);
PAINT BLUE (12500 3550);
FORCEPROP 0 LAST ROOM PVNN_PCH_STBY
J 0
(12500 3950);
DISPLAY 1.021277 (12500 3950);
PAINT ORANGE (12500 3950);
DISPLAY INVISIBLE (12500 3950);
FORCEPROP 1 LAST PATH I74
J 0
(12500 3900);
DISPLAY 0.978723 (12500 3900);
PAINT ORANGE (12500 3900);
DISPLAY INVISIBLE (12500 3900);
FORCEPROP 2 LAST CDS_LOCATION C3L21
J 0
(12500 3850);
DISPLAY 0.617021 (12500 3850);
PAINT AQUA (12500 3850);
DISPLAY INVISIBLE (12500 3850);
FORCEPROP 2 LAST SEC 1
J 0
(12500 3950);
DISPLAY 0.680851 (12500 3950);
PAINT MONO (12500 3950);
DISPLAY INVISIBLE (12500 3950);
FORCEPROP 2 LAST SEC_TYPE SM
J 0
(12500 3950);
DISPLAY 1.021277 (12500 3950);
PAINT ORANGE (12500 3950);
DISPLAY INVISIBLE (12500 3950);
FORCEPROP 2 LAST CDS_LIB mstr_discrete
J 0
(12450 3750);
PAINT ORANGE (12450 3750);
DISPLAY INVISIBLE (12450 3750);
FORCEADD CAPP..1
(12700 3750);
FORCEPROP 1 LAST MATERIAL ALUM
J 0
(12750 3650);
DISPLAY 0.617021 (12750 3650);
PAINT SKYBLUE (12750 3650);
FORCEPROP 1 LAST VOLTAGE 2V
J 0
(12750 3700);
DISPLAY 0.617021 (12750 3700);
PAINT SKYBLUE (12750 3700);
FORCEPROP 1 LAST PACK_TYPE SM
J 0
(12750 3600);
DISPLAY 0.617021 (12750 3600);
PAINT SKYBLUE (12750 3600);
FORCEPROP 1 LAST TOLERANCE 20%
J 0
(12750 3750);
DISPLAY 0.617021 (12750 3750);
PAINT SKYBLUE (12750 3750);
FORCEPROP 1 LAST VALUE 470UF
J 0
(12750 3800);
DISPLAY 0.617021 (12750 3800);
PAINT SKYBLUE (12750 3800);
FORCEPROP 1 LAST LOCATION C7A27
J 0
(12750 3850);
DISPLAY 0.617021 (12750 3850);
PAINT AQUA (12750 3850);
FORCEPROP 1 LASTPIN (12700 3850) $PN 1
J 0
(12710 3835);
DISPLAY 0.617021 (12710 3835);
PAINT ORANGE (12710 3835);
FORCEPROP 1 LASTPIN (12700 3650) $PN 2
J 0
(12710 3635);
DISPLAY 0.617021 (12710 3635);
PAINT ORANGE (12710 3635);
FORCEPROP 1 LAST PART_NUMBER 699013-031
J 0
(12750 3550);
DISPLAY 0.617021 (12750 3550);
PAINT BLUE (12750 3550);
FORCEPROP 0 LAST ROOM PVNN_PCH_STBY
J 0
(12750 3950);
DISPLAY 1.021277 (12750 3950);
PAINT ORANGE (12750 3950);
DISPLAY INVISIBLE (12750 3950);
FORCEPROP 2 LAST SEC 1
J 0
(12750 3950);
DISPLAY 0.680851 (12750 3950);
PAINT MONO (12750 3950);
DISPLAY INVISIBLE (12750 3950);
FORCEPROP 2 LAST SEC_TYPE SM
J 0
(12750 3950);
DISPLAY 1.021277 (12750 3950);
PAINT ORANGE (12750 3950);
DISPLAY INVISIBLE (12750 3950);
FORCEPROP 1 LAST PATH I75
J 0
(12750 3900);
DISPLAY 0.978723 (12750 3900);
PAINT ORANGE (12750 3900);
DISPLAY INVISIBLE (12750 3900);
FORCEPROP 2 LAST CDS_LOCATION C7A27
J 0
(12750 3850);
DISPLAY 0.617021 (12750 3850);
PAINT AQUA (12750 3850);
DISPLAY INVISIBLE (12750 3850);
FORCEPROP 2 LAST CDS_LIB mstr_discrete
J 0
(12700 3750);
PAINT ORANGE (12700 3750);
DISPLAY INVISIBLE (12700 3750);
FORCEADD CAPP..1
(11775 2025);
FORCEPROP 1 LASTPIN (11775 2125) $PN 1
J 0
(11785 2110);
DISPLAY 0.617021 (11785 2110);
PAINT ORANGE (11785 2110);
FORCEPROP 1 LAST PACK_TYPE SM
J 0
(11825 1875);
DISPLAY 0.617021 (11825 1875);
PAINT SKYBLUE (11825 1875);
FORCEPROP 1 LAST TOLERANCE 20%
J 0
(11825 2025);
DISPLAY 0.617021 (11825 2025);
PAINT SKYBLUE (11825 2025);
FORCEPROP 1 LAST VOLTAGE 2V
J 0
(11825 1975);
DISPLAY 0.617021 (11825 1975);
PAINT SKYBLUE (11825 1975);
FORCEPROP 1 LASTPIN (11775 1925) $PN 2
J 0
(11785 1910);
DISPLAY 0.617021 (11785 1910);
PAINT ORANGE (11785 1910);
FORCEPROP 1 LAST LOCATION C3L19
J 0
(11825 2125);
DISPLAY 0.617021 (11825 2125);
PAINT AQUA (11825 2125);
FORCEPROP 1 LAST VALUE 470UF
J 0
(11825 2075);
DISPLAY 0.617021 (11825 2075);
PAINT SKYBLUE (11825 2075);
FORCEPROP 1 LAST MATERIAL ALUM
J 0
(11825 1925);
DISPLAY 0.617021 (11825 1925);
PAINT SKYBLUE (11825 1925);
FORCEPROP 1 LAST PART_NUMBER 699013-031
J 0
(11825 1825);
DISPLAY 0.617021 (11825 1825);
PAINT BLUE (11825 1825);
FORCEPROP 2 LAST SEC 1
J 0
(11825 2225);
DISPLAY 0.680851 (11825 2225);
PAINT MONO (11825 2225);
DISPLAY INVISIBLE (11825 2225);
FORCEPROP 2 LAST SEC_TYPE SM
J 0
(11825 2225);
DISPLAY 1.021277 (11825 2225);
PAINT ORANGE (11825 2225);
DISPLAY INVISIBLE (11825 2225);
FORCEPROP 0 LAST ROOM P1V05_PCH_STBY
J 0
(11825 2225);
DISPLAY 1.021277 (11825 2225);
PAINT ORANGE (11825 2225);
DISPLAY INVISIBLE (11825 2225);
FORCEPROP 1 LAST PATH I76
J 0
(11825 2175);
DISPLAY 0.978723 (11825 2175);
PAINT ORANGE (11825 2175);
DISPLAY INVISIBLE (11825 2175);
FORCEPROP 2 LAST CDS_LOCATION C3L19
J 0
(11825 2125);
DISPLAY 0.617021 (11825 2125);
PAINT AQUA (11825 2125);
DISPLAY INVISIBLE (11825 2125);
FORCEPROP 2 LAST CDS_LIB mstr_discrete
J 0
(11775 2025);
PAINT ORANGE (11775 2025);
DISPLAY INVISIBLE (11775 2025);
FORCEADD CAPP..1
(12025 2025);
FORCEPROP 1 LAST PACK_TYPE SM
J 0
(12075 1875);
DISPLAY 0.617021 (12075 1875);
PAINT SKYBLUE (12075 1875);
FORCEPROP 1 LAST VOLTAGE 2V
J 0
(12075 1975);
DISPLAY 0.617021 (12075 1975);
PAINT SKYBLUE (12075 1975);
FORCEPROP 1 LAST MATERIAL ALUM
J 0
(12075 1925);
DISPLAY 0.617021 (12075 1925);
PAINT SKYBLUE (12075 1925);
FORCEPROP 1 LAST TOLERANCE 20%
J 0
(12075 2025);
DISPLAY 0.617021 (12075 2025);
PAINT SKYBLUE (12075 2025);
FORCEPROP 1 LAST PART_NUMBER 699013-031
J 0
(12075 1825);
DISPLAY 0.617021 (12075 1825);
PAINT BLUE (12075 1825);
FORCEPROP 1 LAST LOCATION C2L46
J 0
(12075 2125);
DISPLAY 0.617021 (12075 2125);
PAINT AQUA (12075 2125);
FORCEPROP 1 LAST VALUE 470UF
J 0
(12075 2075);
DISPLAY 0.617021 (12075 2075);
PAINT SKYBLUE (12075 2075);
FORCEPROP 1 LASTPIN (12025 1925) $PN 2
J 0
(12035 1910);
DISPLAY 0.787234 (12035 1910);
PAINT ORANGE (12035 1910);
DISPLAY INVISIBLE (12035 1910);
FORCEPROP 2 LAST CDS_LIB mstr_discrete
J 0
(12025 2025);
PAINT ORANGE (12025 2025);
DISPLAY INVISIBLE (12025 2025);
FORCEPROP 2 LAST CDS_SEC 1
J 0
(12075 2225);
PAINT MONO (12075 2225);
DISPLAY INVISIBLE (12075 2225);
FORCEPROP 2 LAST $SEC 1
J 0
(12075 2225);
PAINT MONO (12075 2225);
DISPLAY INVISIBLE (12075 2225);
FORCEPROP 2 LAST CDS_LOCATION C2L46
J 0
(12075 2125);
DISPLAY 0.617021 (12075 2125);
PAINT AQUA (12075 2125);
DISPLAY INVISIBLE (12075 2125);
FORCEPROP 1 LAST PATH I77
J 0
(12075 2175);
DISPLAY 0.978723 (12075 2175);
PAINT ORANGE (12075 2175);
DISPLAY INVISIBLE (12075 2175);
FORCEPROP 0 LAST ROOM P1V05_PCH_STBY
J 0
(12075 2225);
DISPLAY 1.021277 (12075 2225);
PAINT ORANGE (12075 2225);
DISPLAY INVISIBLE (12075 2225);
FORCEPROP 1 LASTPIN (12025 2125) $PN 1
J 0
(12035 2110);
DISPLAY 0.787234 (12035 2110);
PAINT ORANGE (12035 2110);
DISPLAY INVISIBLE (12035 2110);
FORCEADD CAPP..1
(12275 2025);
FORCEPROP 1 LAST TOLERANCE 20%
J 0
(12325 2025);
DISPLAY 0.617021 (12325 2025);
PAINT SKYBLUE (12325 2025);
FORCEPROP 1 LAST PART_NUMBER 699013-031
J 0
(12325 1825);
DISPLAY 0.617021 (12325 1825);
PAINT BLUE (12325 1825);
FORCEPROP 1 LAST VOLTAGE 2V
J 0
(12325 1975);
DISPLAY 0.617021 (12325 1975);
PAINT SKYBLUE (12325 1975);
FORCEPROP 1 LAST MATERIAL ALUM
J 0
(12325 1925);
DISPLAY 0.617021 (12325 1925);
PAINT SKYBLUE (12325 1925);
FORCEPROP 1 LAST PACK_TYPE SM
J 0
(12325 1875);
DISPLAY 0.617021 (12325 1875);
PAINT SKYBLUE (12325 1875);
FORCEPROP 1 LAST VALUE 470UF
J 0
(12325 2075);
DISPLAY 0.617021 (12325 2075);
PAINT SKYBLUE (12325 2075);
FORCEPROP 1 LAST LOCATION C8A15
J 0
(12325 2125);
DISPLAY 0.617021 (12325 2125);
PAINT AQUA (12325 2125);
FORCEPROP 0 LAST ROOM P1V05_PCH_STBY
J 0
(12325 2225);
DISPLAY 1.021277 (12325 2225);
PAINT ORANGE (12325 2225);
DISPLAY INVISIBLE (12325 2225);
FORCEPROP 1 LAST PATH I78
J 0
(12325 2175);
DISPLAY 0.978723 (12325 2175);
PAINT ORANGE (12325 2175);
DISPLAY INVISIBLE (12325 2175);
FORCEPROP 2 LAST CDS_LOCATION C8A15
J 0
(12325 2125);
DISPLAY 0.617021 (12325 2125);
PAINT AQUA (12325 2125);
DISPLAY INVISIBLE (12325 2125);
FORCEPROP 2 LAST $SEC 1
J 0
(12325 2225);
PAINT MONO (12325 2225);
DISPLAY INVISIBLE (12325 2225);
FORCEPROP 2 LAST CDS_SEC 1
J 0
(12325 2225);
PAINT MONO (12325 2225);
DISPLAY INVISIBLE (12325 2225);
FORCEPROP 1 LASTPIN (12275 2125) $PN 1
J 0
(12285 2110);
DISPLAY 0.787234 (12285 2110);
PAINT ORANGE (12285 2110);
DISPLAY INVISIBLE (12285 2110);
FORCEPROP 2 LAST CDS_LIB mstr_discrete
J 0
(12275 2025);
PAINT ORANGE (12275 2025);
DISPLAY INVISIBLE (12275 2025);
FORCEPROP 1 LASTPIN (12275 1925) $PN 2
J 0
(12285 1910);
DISPLAY 0.787234 (12285 1910);
PAINT ORANGE (12285 1910);
DISPLAY INVISIBLE (12285 1910);
FORCEADD CAPP..1
(12550 2025);
FORCEPROP 1 LAST LOCATION C2L25
J 0
(12600 2125);
DISPLAY 0.617021 (12600 2125);
PAINT AQUA (12600 2125);
FORCEPROP 1 LAST VALUE 470UF
J 0
(12600 2075);
DISPLAY 0.617021 (12600 2075);
PAINT SKYBLUE (12600 2075);
FORCEPROP 1 LAST TOLERANCE 20%
J 0
(12600 2025);
DISPLAY 0.617021 (12600 2025);
PAINT SKYBLUE (12600 2025);
FORCEPROP 1 LAST PART_NUMBER 699013-031
J 0
(12600 1825);
DISPLAY 0.617021 (12600 1825);
PAINT BLUE (12600 1825);
FORCEPROP 1 LAST MATERIAL ALUM
J 0
(12600 1925);
DISPLAY 0.617021 (12600 1925);
PAINT SKYBLUE (12600 1925);
FORCEPROP 1 LAST VOLTAGE 2V
J 0
(12600 1975);
DISPLAY 0.617021 (12600 1975);
PAINT SKYBLUE (12600 1975);
FORCEPROP 1 LAST PACK_TYPE SM
J 0
(12600 1875);
DISPLAY 0.617021 (12600 1875);
PAINT SKYBLUE (12600 1875);
FORCEPROP 2 LAST $SEC 1
J 0
(12600 2225);
PAINT MONO (12600 2225);
DISPLAY INVISIBLE (12600 2225);
FORCEPROP 2 LAST CDS_SEC 1
J 0
(12600 2225);
PAINT MONO (12600 2225);
DISPLAY INVISIBLE (12600 2225);
FORCEPROP 0 LAST ROOM P1V05_PCH_STBY
J 0
(12600 2225);
DISPLAY 1.021277 (12600 2225);
PAINT ORANGE (12600 2225);
DISPLAY INVISIBLE (12600 2225);
FORCEPROP 1 LAST PATH I79
J 0
(12600 2175);
DISPLAY 0.978723 (12600 2175);
PAINT ORANGE (12600 2175);
DISPLAY INVISIBLE (12600 2175);
FORCEPROP 2 LAST CDS_LOCATION C2L25
J 0
(12600 2125);
DISPLAY 0.617021 (12600 2125);
PAINT AQUA (12600 2125);
DISPLAY INVISIBLE (12600 2125);
FORCEPROP 1 LASTPIN (12550 2125) $PN 1
J 0
(12560 2110);
DISPLAY 0.787234 (12560 2110);
PAINT ORANGE (12560 2110);
DISPLAY INVISIBLE (12560 2110);
FORCEPROP 2 LAST CDS_LIB mstr_discrete
J 0
(12550 2025);
PAINT ORANGE (12550 2025);
DISPLAY INVISIBLE (12550 2025);
FORCEPROP 1 LASTPIN (12550 1925) $PN 2
J 0
(12560 1910);
DISPLAY 0.787234 (12560 1910);
PAINT ORANGE (12560 1910);
DISPLAY INVISIBLE (12560 1910);
FORCEADD GND..1
(11575 3525);
FORCEPROP 3 LASTPIN (11575 3575) SIG_NAME GND\g
J 0
(11585 3585);
DISPLAY 0.659574 (11585 3585);
PAINT MONO (11585 3585);
DISPLAY INVISIBLE (11585 3585);
FORCEPROP 2 LAST CDS_LIB mstr_symbols
J 0
(11575 3525);
DISPLAY 1.617021 (11575 3525);
PAINT ORANGE (11575 3525);
DISPLAY INVISIBLE (11575 3525);
FORCEPROP 1 LAST SIZE 1B
J 0
(11650 3475);
DISPLAY 2.787234 (11650 3475);
PAINT GREEN (11650 3475);
DISPLAY INVISIBLE (11650 3475);
FORCEPROP 1 LAST PATH I8
J 0
(11650 3525);
DISPLAY 0.872340 (11650 3525);
PAINT AQUA (11650 3525);
DISPLAY INVISIBLE (11650 3525);
FORCEPROP 1 LAST VOLTAGE 0.0V
J 0
(11530 3482);
DISPLAY 0.340426 (11530 3482);
PAINT SKYBLUE (11530 3482);
DISPLAY INVISIBLE (11530 3482);
FORCEPROP 2 LAST ROOM PVCCIO_CPU0
J 0
(11025 3600);
DISPLAY 3.127660 (11025 3600);
PAINT WHITE (11025 3600);
DISPLAY INVISIBLE (11025 3600);
FORCEPROP 2 LAST BOM_COST PROC_VRD_PVCCIO_CPU0
J 0
(11200 3600);
DISPLAY 2.340426 (11200 3600);
PAINT WHITE (11200 3600);
DISPLAY INVISIBLE (11200 3600);
FORCEPROP 1 LAST BODY_TYPE PLUMBING
J 0
(11530 3482);
DISPLAY 0.340426 (11530 3482);
PAINT GREEN (11530 3482);
DISPLAY INVISIBLE (11530 3482);
FORCEPROP 1 LAST HDL_POWER GND
J 0
(11575 3675);
DISPLAY 2.787234 (11575 3675);
PAINT GREEN (11575 3675);
DISPLAY INVISIBLE (11575 3675);
FORCEADD GND..1
(9475 850);
FORCEPROP 3 LASTPIN (9475 900) SIG_NAME GND\g
J 0
(9485 910);
DISPLAY 0.659574 (9485 910);
PAINT MONO (9485 910);
DISPLAY INVISIBLE (9485 910);
FORCEPROP 1 LAST PATH I82
J 0
(9550 850);
DISPLAY 0.872340 (9550 850);
PAINT AQUA (9550 850);
DISPLAY INVISIBLE (9550 850);
FORCEPROP 1 LAST SIZE 1B
J 0
(9550 800);
DISPLAY 0.893617 (9550 800);
PAINT GREEN (9550 800);
DISPLAY INVISIBLE (9550 800);
FORCEPROP 2 LAST CDS_LIB mstr_symbols
J 0
(9475 850);
PAINT ORANGE (9475 850);
DISPLAY INVISIBLE (9475 850);
FORCEPROP 1 LAST VOLTAGE 0
J 0
(9475 850);
PAINT SKYBLUE (9475 850);
DISPLAY INVISIBLE (9475 850);
FORCEPROP 2 LAST BOM_COST MEM_VRD_PVPP_AB
J 0
(9150 925);
PAINT MONO (9150 925);
DISPLAY INVISIBLE (9150 925);
FORCEPROP 2 LAST ROOM VCCP_CPU0_VR
J 0
(8925 925);
PAINT ORANGE (8925 925);
DISPLAY INVISIBLE (8925 925);
FORCEPROP 1 LAST BODY_TYPE PLUMBING
J 0
(9430 807);
DISPLAY 0.340426 (9430 807);
PAINT GREEN (9430 807);
DISPLAY INVISIBLE (9430 807);
FORCEPROP 1 LAST HDL_POWER GND
J 0
(9475 1000);
DISPLAY 0.893617 (9475 1000);
PAINT GREEN (9475 1000);
DISPLAY INVISIBLE (9475 1000);
FORCEADD OFFPAGE..1
(7900 1175);
FORCEPROP 2 LAST $XR0 123 
J 0
(7648 1175);
DISPLAY 0.638298 (7648 1175);
PAINT MONO (7648 1175);
FORCEPROP 2 LAST PATH I85
J 0
(7950 1250);
DISPLAY 1.021277 (7950 1250);
PAINT ORANGE (7950 1250);
DISPLAY INVISIBLE (7950 1250);
FORCEPROP 2 LAST CDS_LIB mstr_standard
J 0
(7900 1175);
PAINT ORANGE (7900 1175);
DISPLAY INVISIBLE (7900 1175);
FORCEPROP 1 LAST OFFPAGE TRUE
J 0
(8225 1050);
DISPLAY 1.170213 (8225 1050);
PAINT GREEN (8225 1050);
DISPLAY INVISIBLE (8225 1050);
FORCEPROP 1 LAST COMMENT_BODY TRUE
J 0
(8025 1075);
DISPLAY 1.170213 (8025 1075);
PAINT GREEN (8025 1075);
DISPLAY INVISIBLE (8025 1075);
FORCEADD OFFPAGE..1
(7900 900);
FORCEPROP 2 LAST $XR0 123 
J 0
(7648 900);
DISPLAY 0.638298 (7648 900);
PAINT MONO (7648 900);
FORCEPROP 2 LAST PATH I86
J 0
(7950 975);
DISPLAY 1.021277 (7950 975);
PAINT ORANGE (7950 975);
DISPLAY INVISIBLE (7950 975);
FORCEPROP 2 LAST CDS_LIB mstr_standard
J 0
(7900 900);
PAINT ORANGE (7900 900);
DISPLAY INVISIBLE (7900 900);
FORCEPROP 2 LAST BOM_COST MEM_VRD_PVPP_AB
J 0
(7625 950);
PAINT MONO (7625 950);
DISPLAY INVISIBLE (7625 950);
FORCEPROP 1 LAST OFFPAGE TRUE
J 0
(8225 775);
DISPLAY 0.893617 (8225 775);
PAINT GREEN (8225 775);
DISPLAY INVISIBLE (8225 775);
FORCEPROP 1 LAST COMMENT_BODY TRUE
J 0
(8025 800);
DISPLAY 0.893617 (8025 800);
PAINT GREEN (8025 800);
DISPLAY INVISIBLE (8025 800);
FORCEADD PVNN_PCH_STBY..1
(11550 1575);
FORCEPROP 3 LASTPIN (11550 1525) SIG_NAME PVNN_PCH_STBY\g
J 0
(11560 1535);
DISPLAY 0.659574 (11560 1535);
PAINT MONO (11560 1535);
DISPLAY INVISIBLE (11560 1535);
FORCEPROP 1 LAST VOLTAGE 1.0V
J 0
(11505 1532);
DISPLAY 0.340426 (11505 1532);
PAINT SKYBLUE (11505 1532);
DISPLAY INVISIBLE (11505 1532);
FORCEPROP 2 LAST BOM_COST PROC_VRD_PVCCIO_CPU0
J 0
(11550 1675);
DISPLAY 2.340426 (11550 1675);
PAINT WHITE (11550 1675);
DISPLAY INVISIBLE (11550 1675);
FORCEPROP 2 LAST CDS_LIB mstr_symbols
J 0
(11550 1575);
PAINT ORANGE (11550 1575);
DISPLAY INVISIBLE (11550 1575);
FORCEPROP 1 LAST PATH I87
J 0
(11600 1600);
DISPLAY 0.872340 (11600 1600);
PAINT AQUA (11600 1600);
DISPLAY INVISIBLE (11600 1600);
FORCEPROP 2 LAST ROOM PVCCIO_CPU0
J 0
(11550 1675);
DISPLAY 3.127660 (11550 1675);
PAINT WHITE (11550 1675);
DISPLAY INVISIBLE (11550 1675);
FORCEPROP 1 LAST BODY_TYPE PLUMBING
J 0
(11505 1532);
DISPLAY 0.340426 (11505 1532);
PAINT GREEN (11505 1532);
DISPLAY INVISIBLE (11505 1532);
FORCEPROP 1 LAST HDL_POWER PVNN_PCH_STBY
J 1
(11550 1625);
DISPLAY 0.872340 (11550 1625);
PAINT GREEN (11550 1625);
DISPLAY INVISIBLE (11550 1625);
FORCEADD OFFPAGE..2
(10875 1175);
FORCEPROP 2 LAST $XR0 235 
J 0
(11064 1175);
DISPLAY 0.638298 (11064 1175);
PAINT MONO (11064 1175);
FORCEPROP 2 LAST PATH I88
J 0
(11050 1250);
DISPLAY 1.021277 (11050 1250);
PAINT ORANGE (11050 1250);
DISPLAY INVISIBLE (11050 1250);
FORCEPROP 2 LAST BOM_COST PROC_VRD_PVCCIO_CPU0
J 0
(11075 1225);
DISPLAY 2.340426 (11075 1225);
PAINT WHITE (11075 1225);
DISPLAY INVISIBLE (11075 1225);
FORCEPROP 2 LAST CDS_LIB mstr_standard
J 0
(10875 1175);
PAINT MONO (10875 1175);
DISPLAY INVISIBLE (10875 1175);
FORCEPROP 2 LAST ROOM PVCCIO_CPU0
J 0
(10475 1250);
DISPLAY 3.127660 (10475 1250);
PAINT WHITE (10475 1250);
DISPLAY INVISIBLE (10475 1250);
FORCEPROP 1 LAST OFFPAGE TRUE
J 0
(11200 1050);
PAINT GREEN (11200 1050);
DISPLAY INVISIBLE (11200 1050);
FORCEPROP 1 LAST COMMENT_BODY TRUE
J 0
(10830 1080);
DISPLAY 2.787234 (10830 1080);
PAINT PEACH (10830 1080);
DISPLAY INVISIBLE (10830 1080);
FORCEADD OFFPAGE..2
(10875 950);
FORCEPROP 2 LAST $XR0 235 
J 0
(11064 950);
DISPLAY 0.638298 (11064 950);
PAINT MONO (11064 950);
FORCEPROP 2 LAST PATH I89
J 0
(11050 1025);
DISPLAY 1.021277 (11050 1025);
PAINT ORANGE (11050 1025);
DISPLAY INVISIBLE (11050 1025);
FORCEPROP 2 LAST ROOM PVCCIO_CPU0
J 0
(10475 1025);
DISPLAY 3.127660 (10475 1025);
PAINT WHITE (10475 1025);
DISPLAY INVISIBLE (10475 1025);
FORCEPROP 2 LAST BOM_COST PROC_VRD_PVCCIO_CPU0
J 0
(11075 1000);
DISPLAY 2.340426 (11075 1000);
PAINT WHITE (11075 1000);
DISPLAY INVISIBLE (11075 1000);
FORCEPROP 2 LAST CDS_LIB mstr_standard
J 0
(10875 950);
PAINT MONO (10875 950);
DISPLAY INVISIBLE (10875 950);
FORCEPROP 1 LAST OFFPAGE TRUE
J 0
(11200 825);
PAINT GREEN (11200 825);
DISPLAY INVISIBLE (11200 825);
FORCEPROP 1 LAST COMMENT_BODY TRUE
J 0
(10830 855);
DISPLAY 2.787234 (10830 855);
PAINT PEACH (10830 855);
DISPLAY INVISIBLE (10830 855);
FORCEADD CAP..1
(11575 3750);
FORCEPROP 1 LAST PACK_TYPE 0805LF
J 0
(11625 3550);
DISPLAY 0.617021 (11625 3550);
PAINT SKYBLUE (11625 3550);
FORCEPROP 1 LAST PART_NUMBER C95333-002
J 0
(11625 3600);
DISPLAY 0.617021 (11625 3600);
PAINT BLUE (11625 3600);
FORCEPROP 1 LAST LOCATION C7A30
J 0
(11625 3850);
DISPLAY 0.617021 (11625 3850);
PAINT AQUA (11625 3850);
FORCEPROP 1 LASTPIN (11575 3850) $PN 1
J 0
(11585 3830);
DISPLAY 0.617021 (11585 3830);
PAINT WHITE (11585 3830);
FORCEPROP 1 LASTPIN (11575 3650) $PN 2
J 0
(11585 3630);
DISPLAY 0.617021 (11585 3630);
PAINT WHITE (11585 3630);
FORCEPROP 1 LAST MATERIAL X6S
J 0
(11625 3650);
DISPLAY 0.617021 (11625 3650);
PAINT SKYBLUE (11625 3650);
FORCEPROP 1 LAST TOLERANCE 20%
J 0
(11625 3700);
DISPLAY 0.617021 (11625 3700);
PAINT SKYBLUE (11625 3700);
FORCEPROP 1 LAST VALUE 22UF
J 0
(11625 3800);
DISPLAY 0.617021 (11625 3800);
PAINT SKYBLUE (11625 3800);
FORCEPROP 2 LAST SEC_TYPE 0805LF
J 0
(11630 3950);
DISPLAY 1.659574 (11630 3950);
PAINT ORANGE (11630 3950);
DISPLAY INVISIBLE (11630 3950);
FORCEPROP 2 LAST BOM_COST PROC_VRD_PVCCIO_CPU0
J 0
(11625 3900);
DISPLAY 2.340426 (11625 3900);
PAINT WHITE (11625 3900);
DISPLAY INVISIBLE (11625 3900);
FORCEPROP 2 LAST SEC 1
J 0
(11630 3950);
DISPLAY 1.106383 (11630 3950);
PAINT MONO (11630 3950);
DISPLAY INVISIBLE (11630 3950);
FORCEPROP 2 LAST CDS_LOCATION C7A30
J 0
(11625 3850);
DISPLAY 0.617021 (11625 3850);
PAINT AQUA (11625 3850);
DISPLAY INVISIBLE (11625 3850);
FORCEPROP 1 LAST PATH I9
J 0
(11625 3900);
DISPLAY 0.978723 (11625 3900);
PAINT WHITE (11625 3900);
DISPLAY INVISIBLE (11625 3900);
FORCEPROP 2 LAST ROOM PVNN_PCH_STBY
J 0
(11625 3900);
DISPLAY 2.340426 (11625 3900);
PAINT WHITE (11625 3900);
DISPLAY INVISIBLE (11625 3900);
FORCEPROP 1 LAST VOLTAGE 4V
J 0
(11625 3750);
DISPLAY 2.340426 (11625 3750);
PAINT SKYBLUE (11625 3750);
DISPLAY INVISIBLE (11625 3750);
FORCEPROP 2 LAST CDS_LIB mstr_discrete
J 0
(11575 3750);
DISPLAY 1.617021 (11575 3750);
PAINT ORANGE (11575 3750);
DISPLAY INVISIBLE (11575 3750);
FORCEADD RES..1
(10475 1400);
FORCEPROP 1 LAST PART_NUMBER G21796-017
J 0
(10325 1300);
DISPLAY 0.617021 (10325 1300);
PAINT BLUE (10325 1300);
FORCEPROP 1 LAST VALUE 100.0
J 2
(10475 1350);
DISPLAY 0.617021 (10475 1350);
PAINT SKYBLUE (10475 1350);
FORCEPROP 1 LAST TOLERANCE 1%
J 0
(10525 1350);
DISPLAY 0.617021 (10525 1350);
PAINT SKYBLUE (10525 1350);
FORCEPROP 1 LAST WATTAGE 1/16W
J 2
(10425 1425);
DISPLAY 0.617021 (10425 1425);
PAINT SKYBLUE (10425 1425);
FORCEPROP 1 LAST PACK_TYPE 0402
J 0
(10600 1350);
DISPLAY 0.617021 (10600 1350);
PAINT SKYBLUE (10600 1350);
FORCEPROP 1 LAST LOCATION R7A13
J 0
(10500 1450);
DISPLAY 0.617021 (10500 1450);
PAINT AQUA (10500 1450);
FORCEPROP 2 LAST CDS_LIB mstr_discrete
J 0
(10475 1400);
PAINT MONO (10475 1400);
DISPLAY INVISIBLE (10475 1400);
FORCEPROP 1 LASTPIN (10375 1400) $PN 1
J 0
(10387 1412);
DISPLAY 0.787234 (10387 1412);
PAINT ORANGE (10387 1412);
DISPLAY INVISIBLE (10387 1412);
FORCEPROP 0 LAST SPOF TRUE
J 0
(10425 1600);
DISPLAY 1.021277 (10425 1600);
PAINT ORANGE (10425 1600);
DISPLAY INVISIBLE (10425 1600);
FORCEPROP 2 LAST CDS_SEC 1
J 0
(10425 1600);
PAINT MONO (10425 1600);
DISPLAY INVISIBLE (10425 1600);
FORCEPROP 2 LAST $SEC 1
J 0
(10425 1600);
PAINT MONO (10425 1600);
DISPLAY INVISIBLE (10425 1600);
FORCEPROP 1 LAST PATH I90
J 0
(10425 1550);
DISPLAY 0.978723 (10425 1550);
PAINT WHITE (10425 1550);
DISPLAY INVISIBLE (10425 1550);
FORCEPROP 2 LAST CDS_LOCATION R7A13
J 0
(10500 1450);
DISPLAY 0.617021 (10500 1450);
PAINT AQUA (10500 1450);
DISPLAY INVISIBLE (10500 1450);
FORCEPROP 0 LAST BOM_COST P1V05_PCH_STBY
J 0
(10525 1725);
DISPLAY 1.021277 (10525 1725);
PAINT ORANGE (10525 1725);
DISPLAY INVISIBLE (10525 1725);
FORCEPROP 1 LAST MATERIAL CHIP
J 0
(10525 1450);
DISPLAY 0.617021 (10525 1450);
PAINT SKYBLUE (10525 1450);
DISPLAY INVISIBLE (10525 1450);
FORCEPROP 0 LAST ROOM P1V05_PCH_STBY
J 0
(10525 1625);
DISPLAY 1.021277 (10525 1625);
PAINT ORANGE (10525 1625);
DISPLAY INVISIBLE (10525 1625);
FORCEPROP 1 LASTPIN (10575 1400) $PN 2
J 0
(10537 1412);
DISPLAY 0.787234 (10537 1412);
PAINT ORANGE (10537 1412);
DISPLAY INVISIBLE (10537 1412);
FORCEADD RES..1
(9850 950);
FORCEPROP 1 LAST LOCATION R7A18
J 0
(9800 1050);
DISPLAY 0.617021 (9800 1050);
PAINT AQUA (9800 1050);
FORCEPROP 1 LAST PART_NUMBER G21497-005
J 0
(9700 1000);
DISPLAY 0.617021 (9700 1000);
PAINT BLUE (9700 1000);
FORCEPROP 1 LAST PACK_TYPE 0402
J 0
(9925 850);
DISPLAY 0.617021 (9925 850);
PAINT SKYBLUE (9925 850);
FORCEPROP 1 LAST TOLERANCE 5%
J 0
(9900 900);
DISPLAY 0.617021 (9900 900);
PAINT SKYBLUE (9900 900);
FORCEPROP 1 LAST MATERIAL CHIP
J 0
(9825 850);
DISPLAY 0.617021 (9825 850);
PAINT SKYBLUE (9825 850);
FORCEPROP 1 LAST VALUE 0.0
J 2
(9850 900);
DISPLAY 0.617021 (9850 900);
PAINT SKYBLUE (9850 900);
FORCEPROP 1 LAST WATTAGE 1/16W
J 2
(9800 850);
DISPLAY 0.617021 (9800 850);
PAINT SKYBLUE (9800 850);
FORCEPROP 1 LAST PATH I92
J 0
(9800 1100);
DISPLAY 0.978723 (9800 1100);
PAINT WHITE (9800 1100);
DISPLAY INVISIBLE (9800 1100);
FORCEPROP 0 LAST ROOM P1V05_PCH_STBY
J 0
(9900 1175);
DISPLAY 1.021277 (9900 1175);
PAINT ORANGE (9900 1175);
DISPLAY INVISIBLE (9900 1175);
FORCEPROP 0 LAST SPOF TRUE
J 0
(9800 1150);
DISPLAY 1.021277 (9800 1150);
PAINT ORANGE (9800 1150);
DISPLAY INVISIBLE (9800 1150);
FORCEPROP 2 LAST $SEC 1
J 0
(9800 1150);
PAINT MONO (9800 1150);
DISPLAY INVISIBLE (9800 1150);
FORCEPROP 2 LAST CDS_LOCATION R7A18
J 0
(9800 1050);
DISPLAY 0.617021 (9800 1050);
PAINT AQUA (9800 1050);
DISPLAY INVISIBLE (9800 1050);
FORCEPROP 0 LAST BOM_COST P1V05_PCH_STBY
J 0
(9900 1275);
DISPLAY 1.021277 (9900 1275);
PAINT ORANGE (9900 1275);
DISPLAY INVISIBLE (9900 1275);
FORCEPROP 2 LAST CDS_SEC 1
J 0
(9800 1150);
PAINT MONO (9800 1150);
DISPLAY INVISIBLE (9800 1150);
FORCEPROP 1 LASTPIN (9950 950) $PN 2
J 0
(9912 962);
DISPLAY 0.787234 (9912 962);
PAINT ORANGE (9912 962);
DISPLAY INVISIBLE (9912 962);
FORCEPROP 1 LASTPIN (9750 950) $PN 1
J 0
(9762 962);
DISPLAY 0.787234 (9762 962);
PAINT ORANGE (9762 962);
DISPLAY INVISIBLE (9762 962);
FORCEPROP 2 LAST CDS_LIB mstr_discrete
J 0
(9850 950);
PAINT MONO (9850 950);
DISPLAY INVISIBLE (9850 950);
FORCEADD RES..1
(8725 1175);
FORCEPROP 2 LAST NO_XNET_CONNECTION 1
J 0
(8675 1375);
PAINT MONO (8675 1375);
FORCEPROP 1 LAST PACK_TYPE 0402
J 0
(8775 1100);
DISPLAY 0.617021 (8775 1100);
PAINT SKYBLUE (8775 1100);
FORCEPROP 1 LASTPIN (8825 1175) $PN 2
J 0
(8787 1187);
DISPLAY 0.617021 (8787 1187);
PAINT ORANGE (8787 1187);
FORCEPROP 1 LAST TOLERANCE 1%
J 0
(8750 1225);
DISPLAY 0.617021 (8750 1225);
PAINT SKYBLUE (8750 1225);
FORCEPROP 1 LAST WATTAGE 1/16W
J 2
(8750 1100);
DISPLAY 0.617021 (8750 1100);
PAINT SKYBLUE (8750 1100);
FORCEPROP 1 LAST PART_NUMBER G21796-066
J 0
(8600 1275);
DISPLAY 0.617021 (8600 1275);
PAINT BLUE (8600 1275);
FORCEPROP 1 LAST LOCATION R7A19
J 0
(8650 1325);
DISPLAY 0.617021 (8650 1325);
PAINT AQUA (8650 1325);
FORCEPROP 1 LAST VALUE 10.0
J 2
(8700 1225);
DISPLAY 0.617021 (8700 1225);
PAINT SKYBLUE (8700 1225);
FORCEPROP 1 LASTPIN (8625 1175) $PN 1
J 0
(8637 1187);
DISPLAY 0.617021 (8637 1187);
PAINT ORANGE (8637 1187);
FORCEPROP 2 LAST BOM_COST P1V05_PCH_STBY
J 0
(8800 1325);
PAINT MONO (8800 1325);
DISPLAY INVISIBLE (8800 1325);
FORCEPROP 2 LAST CDS_LIB mstr_discrete
J 0
(8725 1175);
PAINT MONO (8725 1175);
DISPLAY INVISIBLE (8725 1175);
FORCEPROP 1 LAST MATERIAL CHIP
J 0
(8725 1025);
PAINT SKYBLUE (8725 1025);
DISPLAY INVISIBLE (8725 1025);
FORCEPROP 0 LAST SPOF TRUE
J 0
(8650 1425);
DISPLAY 1.021277 (8650 1425);
PAINT ORANGE (8650 1425);
DISPLAY INVISIBLE (8650 1425);
FORCEPROP 2 LAST SEC_TYPE 0402
J 0
(8525 1400);
DISPLAY 1.021277 (8525 1400);
PAINT ORANGE (8525 1400);
DISPLAY INVISIBLE (8525 1400);
FORCEPROP 2 LAST SEC 1
J 0
(8525 1400);
PAINT MONO (8525 1400);
DISPLAY INVISIBLE (8525 1400);
FORCEPROP 2 LAST CDS_LOCATION R7A19
J 0
(8650 1325);
DISPLAY 0.617021 (8650 1325);
PAINT AQUA (8650 1325);
DISPLAY INVISIBLE (8650 1325);
FORCEPROP 1 LAST PATH I93
J 0
(8675 1325);
DISPLAY 0.978723 (8675 1325);
PAINT WHITE (8675 1325);
DISPLAY INVISIBLE (8675 1325);
FORCEPROP 2 LAST ROOM P1V05_PCH_STBY
J 0
(8675 1275);
PAINT ORANGE (8675 1275);
DISPLAY INVISIBLE (8675 1275);
FORCEADD RES..1
(8750 900);
FORCEPROP 2 LAST NO_XNET_CONNECTION 1
J 0
(8700 1100);
PAINT MONO (8700 1100);
FORCEPROP 1 LAST LOCATION R7A14
J 0
(8700 1000);
DISPLAY 0.617021 (8700 1000);
PAINT AQUA (8700 1000);
FORCEPROP 1 LASTPIN (8850 900) $PN 2
J 0
(8812 912);
DISPLAY 0.617021 (8812 912);
PAINT ORANGE (8812 912);
FORCEPROP 1 LAST PACK_TYPE 0402
J 0
(8775 800);
DISPLAY 0.617021 (8775 800);
PAINT SKYBLUE (8775 800);
FORCEPROP 1 LAST TOLERANCE 1%
J 0
(8800 850);
DISPLAY 0.617021 (8800 850);
PAINT SKYBLUE (8800 850);
FORCEPROP 1 LAST WATTAGE 1/16W
J 2
(8750 800);
DISPLAY 0.617021 (8750 800);
PAINT SKYBLUE (8750 800);
FORCEPROP 1 LAST VALUE 10.0
J 2
(8725 850);
DISPLAY 0.617021 (8725 850);
PAINT SKYBLUE (8725 850);
FORCEPROP 1 LAST PART_NUMBER G21796-066
J 0
(8625 950);
DISPLAY 0.617021 (8625 950);
PAINT BLUE (8625 950);
FORCEPROP 1 LASTPIN (8650 900) $PN 1
J 0
(8662 912);
DISPLAY 0.617021 (8662 912);
PAINT ORANGE (8662 912);
FORCEPROP 2 LAST BOM_COST P1V05_PCH_STBY
J 0
(8825 1050);
PAINT MONO (8825 1050);
DISPLAY INVISIBLE (8825 1050);
FORCEPROP 0 LAST SPOF TRUE
J 0
(8700 1100);
DISPLAY 1.021277 (8700 1100);
PAINT ORANGE (8700 1100);
DISPLAY INVISIBLE (8700 1100);
FORCEPROP 2 LAST SEC_TYPE 0402
J 0
(8550 1125);
DISPLAY 1.021277 (8550 1125);
PAINT ORANGE (8550 1125);
DISPLAY INVISIBLE (8550 1125);
FORCEPROP 1 LAST PATH I94
J 0
(8700 1050);
DISPLAY 0.978723 (8700 1050);
PAINT WHITE (8700 1050);
DISPLAY INVISIBLE (8700 1050);
FORCEPROP 2 LAST SEC 1
J 0
(8550 1125);
PAINT MONO (8550 1125);
DISPLAY INVISIBLE (8550 1125);
FORCEPROP 2 LAST ROOM P1V05_PCH_STBY
J 0
(8700 1000);
PAINT ORANGE (8700 1000);
DISPLAY INVISIBLE (8700 1000);
FORCEPROP 2 LAST CDS_LOCATION R7A14
J 0
(8700 1000);
DISPLAY 0.617021 (8700 1000);
PAINT AQUA (8700 1000);
DISPLAY INVISIBLE (8700 1000);
FORCEPROP 2 LAST CDS_LIB mstr_discrete
J 0
(8750 900);
PAINT MONO (8750 900);
DISPLAY INVISIBLE (8750 900);
FORCEPROP 1 LAST MATERIAL CHIP
J 0
(8750 750);
PAINT SKYBLUE (8750 750);
DISPLAY INVISIBLE (8750 750);
FORCEADD VCC_CORE..1
(5575 4875);
FORCEPROP 3 LASTPIN (5575 4825) SIG_NAME VR_FET_SW_P12V_STBY_PVDDQ_DEF\g
J 0
(5585 4835);
DISPLAY 0.659574 (5585 4835);
PAINT MONO (5585 4835);
DISPLAY INVISIBLE (5585 4835);
FORCEPROP 1 LAST HDL_POWER VR_FET_SW_P12V_STBY_PVDDQ_DEF
J 1
(5575 4925);
DISPLAY 0.617021 (5575 4925);
PAINT GREEN (5575 4925);
FORCEPROP 1 LAST PATH I95
J 0
(5625 4900);
DISPLAY 0.872340 (5625 4900);
PAINT AQUA (5625 4900);
DISPLAY INVISIBLE (5625 4900);
FORCEPROP 2 LAST CDS_LIB mstr_symbols
J 0
(5575 4875);
PAINT ORANGE (5575 4875);
DISPLAY INVISIBLE (5575 4875);
FORCEADD VCC_CORE..1
(5600 3125);
FORCEPROP 3 LASTPIN (5600 3075) SIG_NAME VR_FET_SW_P12V_STBY_PVDDQ_DEF\g
J 0
(5610 3085);
DISPLAY 0.659574 (5610 3085);
PAINT MONO (5610 3085);
DISPLAY INVISIBLE (5610 3085);
FORCEPROP 1 LAST HDL_POWER VR_FET_SW_P12V_STBY_PVDDQ_DEF
J 1
(5600 3175);
DISPLAY 0.617021 (5600 3175);
PAINT GREEN (5600 3175);
FORCEPROP 1 LAST PATH I96
J 0
(5650 3150);
DISPLAY 0.872340 (5650 3150);
PAINT AQUA (5650 3150);
DISPLAY INVISIBLE (5650 3150);
FORCEPROP 2 LAST CDS_LIB mstr_symbols
J 0
(5600 3125);
PAINT ORANGE (5600 3125);
DISPLAY INVISIBLE (5600 3125);
FORCEADD VCC_CORE..1
(12225 1575);
FORCEPROP 3 LASTPIN (12225 1525) SIG_NAME VR_FET_SW_P12V_STBY_PVDDQ_DEF\g
J 0
(12235 1535);
DISPLAY 0.659574 (12235 1535);
PAINT MONO (12235 1535);
DISPLAY INVISIBLE (12235 1535);
FORCEPROP 1 LAST HDL_POWER VR_FET_SW_P12V_STBY_PVDDQ_DEF
J 1
(12225 1625);
DISPLAY 0.617021 (12225 1625);
PAINT GREEN (12225 1625);
FORCEPROP 1 LAST PATH I97
J 0
(12275 1600);
DISPLAY 0.872340 (12275 1600);
PAINT AQUA (12275 1600);
DISPLAY INVISIBLE (12275 1600);
FORCEPROP 2 LAST CDS_LIB mstr_symbols
J 0
(12225 1575);
PAINT ORANGE (12225 1575);
DISPLAY INVISIBLE (12225 1575);
FORCEADD DNS..2
(7005 1045);
PAINT RED (7005 1045);
FORCEPROP 2 LAST CDS_LIB mstr_misc
J 0
(7005 1045);
PAINT ORANGE (7005 1045);
DISPLAY INVISIBLE (7005 1045);
FORCEPROP 1 LAST COMMENT_BODY TRUE
R 1
J 0
(7080 820);
DISPLAY 0.872340 (7080 820);
PAINT GREEN (7080 820);
DISPLAY INVISIBLE (7080 820);
FORCEADD DNS..2
(11980 4420);
PAINT RED (11980 4420);
FORCEPROP 2 LAST CDS_LIB mstr_misc
J 0
(11980 4420);
PAINT ORANGE (11980 4420);
DISPLAY INVISIBLE (11980 4420);
FORCEPROP 1 LAST COMMENT_BODY TRUE
R 1
J 0
(12055 4195);
DISPLAY 0.872340 (12055 4195);
PAINT GREEN (12055 4195);
DISPLAY INVISIBLE (12055 4195);
FORCEADD DNS..2
(12005 2670);
PAINT RED (12005 2670);
FORCEPROP 2 LAST CDS_LIB mstr_misc
J 0
(12005 2670);
PAINT ORANGE (12005 2670);
DISPLAY INVISIBLE (12005 2670);
FORCEPROP 1 LAST COMMENT_BODY TRUE
R 1
J 0
(12080 2445);
DISPLAY 0.872340 (12080 2445);
PAINT GREEN (12080 2445);
DISPLAY INVISIBLE (12080 2445);
FORCEADD INTEL_CORP_BPAGE..1
(13100 225);
FORCEPROP 1 LAST CDS_CON_LAST_MODIFIED Tue Dec 01 11:52:30 2015
J 0
(11675 550);
PAINT GREEN (11675 550);
DISPLAY INVISIBLE (11675 550);
FORCEPROP 1 LAST CUSTOM_TXT_CDS <CURRENT_DESIGN_SHEET> OF <TOTAL_DESIGN_SHEETS>
J 0
(12600 250);
PAINT GREEN (12600 250);
FORCEPROP 1 LAST CUSTOM_TXT_CDS <CON_LAST_MODIFIED>
J 0
(11175 575);
PAINT GREEN (11175 575);
FORCEPROP 2 LAST CUSTOM_TXT_CDS <XR_PAGE_TITLE>
J 0
(5210 5475);
DISPLAY 0.638298 (5210 5475);
PAINT PINK (5210 5475);
DISPLAY INVISIBLE (5210 5475);
FORCEPROP 1 LAST SCH_ADDRESS3 Santa Clara, CA 95052-8119
J 0
(9125 250);
DISPLAY 0.617021 (9125 250);
PAINT GREEN (9125 250);
FORCEPROP 1 LAST SCH_NUMBER H4694802
J 0
(11800 375);
DISPLAY 1.212766 (11800 375);
PAINT YELLOW (11800 375);
FORCEPROP 1 LAST SCH_DEPT BESD
J 1
(8650 325);
DISPLAY 1.212766 (8650 325);
PAINT YELLOW (8650 325);
FORCEPROP 1 LAST SCH_REV 2.420
J 0
(12850 375);
DISPLAY 0.978723 (12850 375);
PAINT YELLOW (12850 375);
FORCEPROP 1 LAST SCH_ADDRESS1 2200 Mission College Blvd.
J 0
(9125 350);
DISPLAY 0.617021 (9125 350);
PAINT GREEN (9125 350);
FORCEPROP 1 LAST SCH_ADDRESS2 P.O. BOX 58119
J 0
(9125 300);
DISPLAY 0.617021 (9125 300);
PAINT GREEN (9125 300);
FORCEPROP 1 LAST SCH_TITLE PVNN P1V05 PCH STBY VR (2 OF 2)
J 0
(5250 350);
DISPLAY 1.212766 (5250 350);
PAINT ORANGE (5250 350);
FORCEPROP 2 LAST CDS_LIB mstr_symbols
J 0
(13100 225);
PAINT ORANGE (13100 225);
DISPLAY INVISIBLE (13100 225);
FORCEPROP 2 LAST PAGE_BORDER TRUE
J 0
(5210 5475);
DISPLAY 0.851064 (5210 5475);
PAINT PINK (5210 5475);
DISPLAY INVISIBLE (5210 5475);
FORCEPROP 1 LAST COMMENT_BODY TRUE
J 0
(13112 237);
DISPLAY 0.468085 (13112 237);
PAINT GREEN (13112 237);
DISPLAY INVISIBLE (13112 237);
FORCEPROP 2 LAST CDS_XR_PAGE_TITLE CR-236 : @BASEBOARD_FAB2_LIB.BASEBOARD_FAB2(SCH_1):PAGE236
J 0
(5210 5475);
DISPLAY 0.638298 (5210 5475);
PAINT PINK (5210 5475);
DISPLAY INVISIBLE (5210 5475);
WIRE 16 -1 (10200 3850)(10375 3850);
WIRE 16 -1 (10375 3800)(10375 3850);
WIRE 16 -1 (10375 3750)(10375 3800);
WIRE 16 -1 (10375 3800)(10200 3800);
WIRE 16 -1 (10375 3700)(10375 3750);
WIRE 16 -1 (10375 3750)(10200 3750);
WIRE 16 -1 (10375 3625)(10375 3700);
WIRE 16 -1 (10375 3700)(10200 3700);
WIRE 16 -1 (11975 4325)(11975 4225);
WIRE 16 -1 (12000 2575)(12000 2475);
WIRE 16 -1 (9200 4500)(9075 4500);
WIRE 16 -1 (9075 4500)(9075 4600);
WIRE 16 -1 (9200 4600)(9075 4600);
WIRE 16 -1 (9075 4600)(8375 4600);
WIRE 16 -1 (8375 4600)(8375 5025);
WIRE 16 -1 (8375 5025)(7750 5025);
WIRE 16 -1 (8375 5025)(8375 5075);
WIRE 16 -1 (7750 5025)(7625 5025);
WIRE 16 -1 (7750 4650)(7750 5025);
WIRE 16 -1 (7625 4650)(7625 5025);
WIRE 16 -1 (7625 5025)(7275 5025);
WIRE 16 -1 (8975 1900)(8975 1800);
WIRE 16 -1 (8975 3650)(8975 3525);
WIRE 16 -1 (10775 4100)(10775 4175);
WIRE 16 -1 (10750 3450)(10750 3425);
WIRE 16 -1 (10750 2475)(10750 2450);
WIRE 16 -1 (10800 1725)(10800 1700);
WIRE 16 -1 (7750 4450)(7750 4225);
WIRE 16 -1 (7750 4225)(7625 4225);
WIRE 16 -1 (7625 4450)(7625 4225);
WIRE 16 -1 (7625 4225)(6925 4225);
WIRE 16 -1 (6925 4400)(6925 4225);
WIRE 16 -1 (6925 4225)(6550 4225);
WIRE 16 -1 (6550 4425)(6550 4225);
WIRE 16 -1 (6550 4225)(6300 4225);
WIRE 16 -1 (6300 4400)(6300 4225);
WIRE 16 -1 (6300 4225)(6075 4225);
WIRE 16 -1 (6075 4425)(6075 4225);
WIRE 16 -1 (6075 4225)(5825 4225);
WIRE 16 -1 (5825 4400)(5825 4225);
WIRE 16 -1 (5825 4225)(5575 4225);
WIRE 16 -1 (6075 4425)(6050 4425);
WIRE 16 -1 (5575 4425)(5575 4225);
WIRE 16 -1 (5575 4125)(5575 4225);
WIRE 16 -1 (7700 2750)(7700 2475);
WIRE 16 -1 (7700 2475)(7550 2475);
WIRE 16 -1 (7550 2750)(7550 2475);
WIRE 16 -1 (6850 2475)(7550 2475);
WIRE 16 -1 (6850 2750)(6850 2475);
WIRE 16 -1 (6850 2475)(6575 2475);
WIRE 16 -1 (6575 2750)(6575 2475);
WIRE 16 -1 (6575 2475)(6350 2475);
WIRE 16 -1 (6350 2725)(6350 2475);
WIRE 16 -1 (6350 2475)(6100 2475);
WIRE 16 -1 (6100 2725)(6100 2475);
WIRE 16 -1 (6100 2475)(5850 2475);
WIRE 16 -1 (5850 2750)(5850 2475);
WIRE 16 -1 (5850 2475)(5600 2475);
WIRE 16 -1 (5600 2725)(5600 2475);
WIRE 16 -1 (5600 2400)(5600 2475);
WIRE 16 -1 (9225 2750)(9125 2750);
WIRE 16 -1 (9125 2750)(9125 2850);
WIRE 16 -1 (9225 2850)(9125 2850);
WIRE 16 -1 (8375 2850)(9125 2850);
WIRE 16 -1 (8375 2850)(8375 3275);
WIRE 16 -1 (7700 3275)(8375 3275);
WIRE 16 -1 (8375 3275)(8375 3350);
WIRE 16 -1 (7550 3275)(7700 3275);
WIRE 16 -1 (7700 2950)(7700 3275);
WIRE 16 -1 (7175 3275)(7550 3275);
WIRE 16 -1 (7550 2950)(7550 3275);
WIRE 16 -1 (10225 2100)(10375 2100);
WIRE 16 -1 (10375 2050)(10375 2100);
WIRE 16 -1 (10375 2000)(10375 2050);
WIRE 16 -1 (10375 2050)(10225 2050);
WIRE 16 -1 (10375 1950)(10375 2000);
WIRE 16 -1 (10375 2000)(10225 2000);
WIRE 16 -1 (10375 1900)(10375 1950);
WIRE 16 -1 (10375 1950)(10225 1950);
WIRE 16 -1 (12550 1925)(12550 1875);
WIRE 16 -1 (12550 1875)(12275 1875);
WIRE 16 -1 (12275 1925)(12275 1875);
WIRE 16 -1 (12275 1875)(12025 1875);
WIRE 16 -1 (12025 1925)(12025 1875);
WIRE 16 -1 (12025 1875)(11775 1875);
WIRE 16 -1 (11775 1925)(11775 1875);
WIRE 16 -1 (11775 1875)(11500 1875);
WIRE 16 -1 (11500 1875)(11500 1925);
WIRE 16 -1 (11500 1850)(11500 1875);
WIRE 16 -1 (9225 2650)(9125 2650);
WIRE 16 -1 (9125 2650)(9125 1600);
WIRE 16 -1 (9125 1600)(11375 1600);
WIRE 16 -1 (11375 1600)(11375 2250);
WIRE 16 -1 (11300 2250)(11375 2250);
WIRE 16 -1 (11375 2250)(11500 2250);
WIRE 16 -1 (11500 2125)(11500 2250);
WIRE 16 -1 (11500 2250)(11775 2250);
WIRE 16 -1 (11775 2125)(11775 2250);
WIRE 16 -1 (11775 2250)(12025 2250);
WIRE 16 -1 (12025 2125)(12025 2250);
WIRE 16 -1 (12025 2250)(12275 2250);
WIRE 16 -1 (12275 2125)(12275 2250);
WIRE 16 -1 (12275 2250)(12550 2250);
WIRE 16 -1 (12550 2125)(12550 2250);
WIRE 16 -1 (12550 2250)(12550 2300);
WIRE 16 -1 (7675 1300)(7450 1300);
WIRE 16 -1 (7675 1450)(7675 1300);
WIRE 16 -1 (7650 850)(7425 850);
WIRE 16 -1 (7650 675)(7650 850);
WIRE 16 -1 (12350 1125)(12350 975);
WIRE 16 -1 (11975 1150)(11975 975);
WIRE 16 -1 (9200 4400)(9075 4400);
WIRE 16 -1 (9075 4400)(9075 3325);
WIRE 16 -1 (9075 3325)(11350 3325);
WIRE 16 -1 (11350 3325)(11350 3950);
WIRE 16 -1 (11250 3950)(11350 3950);
WIRE 16 -1 (11350 3950)(11575 3950);
WIRE 16 -1 (11575 3850)(11575 3950);
WIRE 16 -1 (11575 3950)(11875 3950);
WIRE 16 -1 (11875 3850)(11875 3950);
WIRE 16 -1 (11875 3950)(12175 3950);
WIRE 16 -1 (12175 3850)(12175 3950);
WIRE 16 -1 (12175 3950)(12450 3950);
WIRE 16 -1 (12450 3850)(12450 3950);
WIRE 16 -1 (12450 3950)(12700 3950);
WIRE 16 -1 (12700 3850)(12700 3950);
WIRE 16 -1 (12700 3950)(12700 4025);
WIRE 16 -1 (12700 3650)(12700 3575);
WIRE 16 -1 (12700 3575)(12450 3575);
WIRE 16 -1 (12450 3650)(12450 3575);
WIRE 16 -1 (12450 3575)(12175 3575);
WIRE 16 -1 (12175 3650)(12175 3575);
WIRE 16 -1 (12175 3575)(11875 3575);
WIRE 16 -1 (11875 3650)(11875 3575);
WIRE 16 -1 (11875 3575)(11575 3575);
WIRE 16 -1 (11575 3575)(11575 3650);
WIRE 16 -1 (9475 950)(9750 950);
WIRE 16 -1 (9475 900)(9475 950);
WIRE 16 -1 (10575 1400)(11550 1400);
WIRE 16 -1 (11550 1400)(11550 1525);
WIRE 16 -1 (9200 4750)(8900 4750);
WIRE 16 -1 (8900 4750)(8900 4700);
WIRE 16 -1 (9200 4700)(8900 4700);
WIRE 16 -1 (8900 4700)(6550 4700);
WIRE 16 -1 (6550 4625)(6550 4700);
WIRE 16 -1 (6550 4700)(6300 4700);
WIRE 16 -1 (6300 4600)(6300 4700);
WIRE 16 -1 (6300 4700)(6050 4700);
WIRE 16 -1 (6050 4625)(6050 4700);
WIRE 16 -1 (6050 4700)(5825 4700);
WIRE 16 -1 (5825 4600)(5825 4700);
WIRE 16 -1 (5825 4700)(5575 4700);
WIRE 16 -1 (5575 4625)(5575 4700);
WIRE 16 -1 (5575 4825)(5575 4700);
WIRE 16 -1 (9225 2950)(9050 2950);
WIRE 16 -1 (9050 3000)(9050 2950);
WIRE 16 -1 (9050 3000)(9225 3000);
WIRE 16 -1 (9050 3000)(6575 3000);
WIRE 16 -1 (6575 2950)(6575 3000);
WIRE 16 -1 (6575 3000)(6350 3000);
WIRE 16 -1 (6350 2925)(6350 3000);
WIRE 16 -1 (6350 3000)(6100 3000);
WIRE 16 -1 (6100 2925)(6100 3000);
WIRE 16 -1 (6100 3000)(5850 3000);
WIRE 16 -1 (5850 2950)(5850 3000);
WIRE 16 -1 (5850 3000)(5600 3000);
WIRE 16 -1 (5600 2925)(5600 3000);
WIRE 16 -1 (5600 3075)(5600 3000);
WIRE 16 -1 (12350 1325)(12350 1450);
WIRE 16 -1 (12225 1450)(12350 1450);
WIRE 16 -1 (11975 1450)(12225 1450);
WIRE 16 -1 (12225 1525)(12225 1450);
WIRE 16 -1 (11975 1350)(11975 1450);
WIRE 16 -1 (8975 3225)(11900 3225);
FORCEPROP 2 LAST SIG_NAME VR_P1V05_PCH_BIREF1
J 2
(11960 3236);
DISPLAY 0.617021 (11960 3236);
PAINT ORANGE (11960 3236);
WIRE 16 -1 (8975 2300)(8975 3225);
WIRE 16 -1 (9225 2300)(8975 2300);
WIRE 16 -1 (8975 2100)(8975 2300);
WIRE 16 2175 (6700 2375)(7575 2375);
WIRE 16 2175 (6700 2375)(6700 1850);
WIRE 16 2175 (7575 2375)(7575 1850);
WIRE 16 2175 (6700 1850)(7575 1850);
WIRE 16 -1 (6900 1900)(8800 1900);
FORCEPROP 2 LAST SIG_NAME VR_P1V05_PCH_STBY_PH1_PHASE
J 0
(6940 1910);
DISPLAY 0.617021 (6940 1910);
PAINT ORANGE (6940 1910);
FORCEPROP 2 LASTPROP $XRERR UNIQUE?
J 0
(6700 1910);
DISPLAY 0.638298 (6700 1910);
PAINT MONO (6700 1910);
DISPLAY INVISIBLE (6700 1910);
WIRE 16 -1 (6900 1900)(6900 1975);
WIRE 16 -1 (8800 1900)(8800 2150);
WIRE 16 -1 (8800 2150)(9225 2150);
WIRE 16 -1 (6500 2400)(9225 2400);
FORCEPROP 2 LAST SIG_NAME VR_P1V05_PCH_STBY_PWM1
J 0
(6525 2424);
DISPLAY 0.617021 (6525 2424);
PAINT ORANGE (6525 2424);
WIRE 16 2175 (7250 2975)(7950 2975);
WIRE 16 2175 (7250 2975)(7250 2525);
WIRE 16 2175 (7950 2975)(7950 2525);
WIRE 16 2175 (7250 2525)(7950 2525);
WIRE 16 -1 (6850 3050)(9225 3050);
FORCEPROP 2 LAST SIG_NAME VR_P1V05_PCH_STBY_PH1_VCIN
J 0
(6890 3060);
DISPLAY 0.617021 (6890 3060);
PAINT ORANGE (6890 3060);
FORCEPROP 2 LASTPROP $XRERR UNIQUE?
J 0
(6650 3060);
DISPLAY 0.638298 (6650 3060);
PAINT MONO (6650 3060);
DISPLAY INVISIBLE (6650 3060);
WIRE 16 -1 (6850 3050)(6850 3275);
WIRE 16 -1 (6850 2950)(6850 3050);
WIRE 16 -1 (6850 3275)(6975 3275);
WIRE 3 2175 (7650 2100)(8100 2100);
WIRE 3 2175 (7650 2375)(7650 2100);
WIRE 3 2175 (8100 2375)(8100 2100);
WIRE 3 2175 (7650 2375)(8100 2375);
WIRE 16 -1 (10225 2850)(12000 2850);
FORCEPROP 0 LAST SIG_NAME VR_P1V05_PCH_STBY_OCSET
J 0
(10375 2860);
DISPLAY 0.617021 (10375 2860);
PAINT ORANGE (10375 2860);
FORCEPROP 2 LASTPROP $XRERR UNIQUE?
J 0
(10135 2860);
DISPLAY 0.638298 (10135 2860);
PAINT MONO (10135 2860);
DISPLAY INVISIBLE (10135 2860);
WIRE 16 -1 (12000 2850)(12000 2775);
WIRE 3 2175 (10525 4000)(11000 4000);
WIRE 3 2175 (10525 4000)(10525 3350);
WIRE 3 2175 (11000 4000)(11000 3350);
WIRE 3 2175 (10525 3350)(11000 3350);
WIRE 3 2175 (10600 2750)(11050 2750);
WIRE 3 2175 (10600 2750)(10600 2325);
WIRE 3 2175 (11050 2750)(11050 2325);
WIRE 3 2175 (10600 2325)(11050 2325);
WIRE 3 2175 (10575 2300)(11075 2300);
WIRE 3 2175 (10575 2300)(10575 1625);
WIRE 3 2175 (11075 2300)(11075 1625);
WIRE 3 2175 (10575 1625)(11075 1625);
WIRE 16 -1 (10225 2250)(10800 2250);
FORCEPROP 2 LAST SIG_NAME VR_P1V05_PCH_STBY_PH1_PHASE_SW
J 0
(10215 2260);
DISPLAY 0.617021 (10215 2260);
PAINT ORANGE (10215 2260);
FORCEPROP 2 LASTPROP $XRERR UNIQUE?
J 0
(9975 2260);
DISPLAY 0.638298 (9975 2260);
PAINT MONO (9975 2260);
DISPLAY INVISIBLE (9975 2260);
WIRE 16 -1 (10225 2250)(10225 2200);
WIRE 16 -1 (10800 2250)(11100 2250);
WIRE 16 -1 (10800 2175)(10800 2250);
WIRE 16 682 (9350 1525)(10775 1525);
WIRE 16 682 (9350 1525)(9350 1325);
WIRE 16 682 (10775 750)(10775 1525);
WIRE 16 682 (8475 750)(10775 750);
WIRE 16 682 (9350 1325)(8475 1325);
WIRE 16 682 (8475 1325)(8475 750);
WIRE 3 2175 (10700 4500)(11175 4500);
WIRE 3 2175 (10700 4500)(10700 4025);
WIRE 3 2175 (11175 4500)(11175 4025);
WIRE 3 2175 (10700 4025)(11175 4025);
WIRE 16 -1 (9225 2500)(8325 2500);
FORCEPROP 0 LAST SIG_NAME TP_P1V05_PCH_GL_0
J 0
(8340 2510);
DISPLAY 0.617021 (8340 2510);
PAINT ORANGE (8340 2510);
FORCEPROP 2 LASTPROP $XRERR UNIQUE?
J 0
(8085 2500);
DISPLAY 0.638298 (8085 2500);
PAINT MONO (8085 2500);
DISPLAY INVISIBLE (8085 2500);
WIRE 3 2175 (8725 2275)(9325 2275);
WIRE 3 2175 (8725 2275)(8725 1700);
WIRE 3 2175 (9325 2275)(9325 1700);
WIRE 3 2175 (8725 1700)(9325 1700);
WIRE 16 -1 (10200 3950)(10750 3950);
FORCEPROP 2 LAST SIG_NAME VR_PVNN_PCH_PH1_PHASE_SW
J 0
(10390 3960);
DISPLAY 0.617021 (10390 3960);
PAINT ORANGE (10390 3960);
FORCEPROP 2 LASTPROP $XRERR UNIQUE?
J 0
(10150 3960);
DISPLAY 0.638298 (10150 3960);
PAINT MONO (10150 3960);
DISPLAY INVISIBLE (10150 3960);
WIRE 16 -1 (10750 3950)(11050 3950);
WIRE 16 -1 (10750 3925)(10750 3950);
WIRE 16 -1 (10200 4425)(10775 4425);
FORCEPROP 2 LAST SIG_NAME A_TSENSE_PVNN_PCH_TMON
J 2
(10700 4439);
DISPLAY 0.617021 (10700 4439);
PAINT ORANGE (10700 4439);
WIRE 16 -1 (10200 4425)(10200 4300);
WIRE 16 -1 (10775 4425)(11300 4425);
WIRE 16 -1 (10775 4375)(10775 4425);
WIRE 3 2175 (8675 4000)(9300 4000);
WIRE 3 2175 (8675 4000)(8675 3425);
WIRE 3 2175 (9300 4000)(9300 3425);
WIRE 3 2175 (8675 3425)(9300 3425);
WIRE 16 -1 (6825 3650)(8775 3650);
FORCEPROP 2 LAST SIG_NAME VR_PVNN_PCH_PH1_PHASE
J 0
(6940 3660);
DISPLAY 0.617021 (6940 3660);
PAINT ORANGE (6940 3660);
FORCEPROP 2 LASTPROP $XRERR UNIQUE?
J 0
(6700 3660);
DISPLAY 0.638298 (6700 3660);
PAINT MONO (6700 3660);
DISPLAY INVISIBLE (6700 3660);
WIRE 16 -1 (6825 3650)(6825 3725);
WIRE 16 -1 (8775 3650)(8775 3900);
WIRE 16 -1 (8775 3900)(9200 3900);
WIRE 16 -1 (9200 3950)(8775 3950);
WIRE 16 -1 (8775 3950)(8775 4025);
WIRE 16 -1 (8775 4025)(7950 4025);
FORCEPROP 0 LAST SIG_NAME VR_PVNN_PCH_PH1_BOOT_R
J 0
(8165 4035);
DISPLAY 0.617021 (8165 4035);
PAINT ORANGE (8165 4035);
FORCEPROP 2 LASTPROP $XRERR UNIQUE?
J 0
(7925 4035);
DISPLAY 0.638298 (7925 4035);
PAINT MONO (7925 4035);
DISPLAY INVISIBLE (7925 4035);
WIRE 3 2175 (7600 4125)(8150 4125);
WIRE 3 2175 (7600 4125)(7600 3825);
WIRE 3 2175 (8150 4125)(8150 3825);
WIRE 3 2175 (7600 3825)(8150 3825);
WIRE 16 -1 (7750 4025)(6825 4025);
FORCEPROP 0 LAST SIG_NAME VR_PVNN_PCH_PH1_BOOT
J 0
(6890 4035);
DISPLAY 0.617021 (6890 4035);
PAINT ORANGE (6890 4035);
FORCEPROP 2 LASTPROP $XRERR UNIQUE?
J 0
(6650 4035);
DISPLAY 0.638298 (6650 4035);
PAINT MONO (6650 4035);
DISPLAY INVISIBLE (6650 4035);
WIRE 16 -1 (6825 3925)(6825 4025);
WIRE 16 2175 (6575 4100)(7525 4100);
WIRE 16 2175 (6575 4100)(6575 3600);
WIRE 16 2175 (7525 4100)(7525 3600);
WIRE 16 2175 (6575 3600)(7525 3600);
WIRE 16 -1 (6450 4150)(9200 4150);
FORCEPROP 2 LAST SIG_NAME VR_PVNN_PCH_PWM1
J 0
(6450 4174);
DISPLAY 0.617021 (6450 4174);
PAINT ORANGE (6450 4174);
WIRE 16 -1 (9225 2550)(8325 2550);
FORCEPROP 0 LAST SIG_NAME TP_P1V05_PCH_GL_1
J 0
(8340 2560);
DISPLAY 0.617021 (8340 2560);
PAINT ORANGE (8340 2560);
FORCEPROP 2 LASTPROP $XRERR UNIQUE?
J 0
(8085 2550);
DISPLAY 0.638298 (8085 2550);
PAINT MONO (8085 2550);
DISPLAY INVISIBLE (8085 2550);
WIRE 16 -1 (9225 2200)(8800 2200);
WIRE 16 -1 (8800 2200)(8800 2300);
WIRE 16 -1 (8800 2300)(8000 2300);
FORCEPROP 0 LAST SIG_NAME VR_P1V05_PCH_STBY_PH1_BOOT_R
J 0
(8115 2310);
DISPLAY 0.617021 (8115 2310);
PAINT ORANGE (8115 2310);
FORCEPROP 2 LASTPROP $XRERR UNIQUE?
J 0
(7875 2310);
DISPLAY 0.638298 (7875 2310);
PAINT MONO (7875 2310);
DISPLAY INVISIBLE (7875 2310);
WIRE 16 -1 (7800 2300)(6900 2300);
FORCEPROP 0 LAST SIG_NAME VR_P1V05_PCH_STBY_PH1_BOOT
J 0
(6965 2310);
DISPLAY 0.617021 (6965 2310);
PAINT ORANGE (6965 2310);
FORCEPROP 2 LASTPROP $XRERR UNIQUE?
J 0
(6725 2310);
DISPLAY 0.638298 (6725 2310);
PAINT MONO (6725 2310);
DISPLAY INVISIBLE (6725 2310);
WIRE 16 -1 (6900 2175)(6900 2300);
WIRE 16 -1 (7000 1150)(7000 1300);
WIRE 16 -1 (7250 1300)(7000 1300);
WIRE 16 -1 (7000 1300)(6900 1300);
WIRE 16 -1 (6900 1300)(6900 1150);
WIRE 16 -1 (6900 1150)(6500 1150);
WIRE 16 -1 (6500 1150)(6500 1275);
WIRE 16 -1 (6500 1275)(5800 1275);
FORCEPROP 0 LAST SIG_NAME VSENSE_P1V05_PCH_STBY_AVSP
J 0
(5790 1285);
DISPLAY 0.617021 (5790 1285);
PAINT ORANGE (5790 1285);
WIRE 16 -1 (8625 1175)(7950 1175);
FORCEPROP 0 LAST SIG_NAME VSENSE_PVNN_PCH_STBY_QAT
J 0
(7940 1185);
DISPLAY 0.617021 (7940 1185);
PAINT ORANGE (7940 1185);
WIRE 16 -1 (9200 4050)(8975 4050);
WIRE 16 -1 (8975 4050)(8975 5125);
WIRE 16 -1 (8975 3850)(8975 4050);
WIRE 16 -1 (8975 5125)(11250 5125);
FORCEPROP 2 LAST SIG_NAME VR_PVNN_PCH_AIREF1
J 0
(10361 5132);
DISPLAY 0.617021 (10361 5132);
PAINT ORANGE (10361 5132);
WIRE 16 -1 (6925 4800)(9200 4800);
FORCEPROP 2 LAST SIG_NAME VR_PVNN_PCH_PH1_VCIN
J 0
(6965 4810);
DISPLAY 0.617021 (6965 4810);
PAINT ORANGE (6965 4810);
FORCEPROP 2 LASTPROP $XRERR UNIQUE?
J 0
(6725 4810);
DISPLAY 0.638298 (6725 4810);
PAINT MONO (6725 4810);
DISPLAY INVISIBLE (6725 4810);
WIRE 16 -1 (6925 4800)(6925 5025);
WIRE 16 -1 (6925 4600)(6925 4800);
WIRE 16 -1 (6925 5025)(7075 5025);
WIRE 16 -1 (10200 4600)(11975 4600);
FORCEPROP 0 LAST SIG_NAME VR_PVNN_PCH_STBY_OCSET
J 0
(10290 4610);
DISPLAY 0.617021 (10290 4610);
PAINT ORANGE (10290 4610);
FORCEPROP 2 LASTPROP $XRERR UNIQUE?
J 0
(10050 4610);
DISPLAY 0.638298 (10050 4610);
PAINT MONO (10050 4610);
DISPLAY INVISIBLE (10050 4610);
WIRE 16 -1 (11975 4600)(11975 4525);
WIRE 16 -1 (10750 3775)(10750 3700);
WIRE 16 -1 (5800 925)(6500 925);
FORCEPROP 0 LAST SIG_NAME VSENSE_P1V05_PCH_STBY_AVSN
J 0
(5790 935);
DISPLAY 0.617021 (5790 935);
PAINT ORANGE (5790 935);
WIRE 16 -1 (6500 925)(6500 1075);
WIRE 16 -1 (6500 1075)(6900 1075);
WIRE 16 -1 (6900 1075)(6900 850);
WIRE 16 -1 (7000 850)(6900 850);
WIRE 16 -1 (7225 850)(7000 850);
WIRE 16 -1 (7000 950)(7000 850);
WIRE 16 -1 (10800 2025)(10800 1975);
WIRE 16 -1 (9550 1400)(10375 1400);
WIRE 16 -1 (9550 1175)(9550 1400);
WIRE 16 -1 (10825 1175)(9550 1175);
FORCEPROP 0 LAST SIG_NAME VSENSE_PVNN_PCH_STBY_AVSP
J 0
(10065 1185);
DISPLAY 0.617021 (10065 1185);
PAINT ORANGE (10065 1185);
WIRE 16 -1 (8925 1175)(9550 1175);
WIRE 16 -1 (8825 1175)(8925 1175);
WIRE 16 -1 (8925 900)(8925 1175);
WIRE 16 -1 (8850 900)(8925 900);
WIRE 16 -1 (10225 2700)(10750 2700);
FORCEPROP 2 LAST SIG_NAME A_TSENSE_P1V05_PCH_STBY_TMON
J 0
(10250 2714);
DISPLAY 0.617021 (10250 2714);
PAINT ORANGE (10250 2714);
WIRE 16 -1 (10225 2700)(10225 2550);
WIRE 16 -1 (10750 2700)(11175 2700);
WIRE 16 -1 (10750 2675)(10750 2700);
WIRE 16 -1 (10225 2800)(10925 2800);
FORCEPROP 2 LAST SIG_NAME NC_P1V05_PCH_STBY_PH1_P31
J 0
(10375 2810);
DISPLAY 0.617021 (10375 2810);
PAINT ORANGE (10375 2810);
FORCEPROP 2 LASTPROP $XRERR UNIQUE?
J 0
(10955 2800);
DISPLAY 0.638298 (10955 2800);
PAINT MONO (10955 2800);
DISPLAY INVISIBLE (10955 2800);
WIRE 16 -1 (10225 3050)(11250 3050);
FORCEPROP 2 LAST SIG_NAME ISENSE_P1V05_PCH_STBY_PH1_IMON
J 0
(10375 3064);
DISPLAY 0.617021 (10375 3064);
PAINT ORANGE (10375 3064);
WIRE 16 -1 (7950 900)(8650 900);
FORCEPROP 0 LAST SIG_NAME VSENSE_PVNN_PCH_STBY_FPK
J 0
(7965 910);
DISPLAY 0.617021 (7965 910);
PAINT ORANGE (7965 910);
WIRE 16 -1 (9950 950)(10825 950);
FORCEPROP 0 LAST SIG_NAME VSENSE_PVNN_PCH_STBY_AVSN
J 0
(10040 960);
DISPLAY 0.617021 (10040 960);
PAINT ORANGE (10040 960);
WIRE 16 -1 (9200 4300)(8300 4300);
FORCEPROP 0 LAST SIG_NAME TP_PVNN_PCH_GL_1
J 0
(8315 4310);
DISPLAY 0.617021 (8315 4310);
PAINT ORANGE (8315 4310);
FORCEPROP 2 LASTPROP $XRERR UNIQUE?
J 0
(8060 4300);
DISPLAY 0.638298 (8060 4300);
PAINT MONO (8060 4300);
DISPLAY INVISIBLE (8060 4300);
WIRE 16 -1 (9200 4250)(8300 4250);
FORCEPROP 0 LAST SIG_NAME TP_PVNN_PCH_GL_0
J 0
(8315 4260);
DISPLAY 0.617021 (8315 4260);
PAINT ORANGE (8315 4260);
FORCEPROP 2 LASTPROP $XRERR UNIQUE?
J 0
(8060 4250);
DISPLAY 0.638298 (8060 4250);
PAINT MONO (8060 4250);
DISPLAY INVISIBLE (8060 4250);
WIRE 16 -1 (10200 4800)(11225 4800);
FORCEPROP 2 LAST SIG_NAME ISENSE_PVNN_PCH_PH1_IMON
J 2
(11075 4814);
DISPLAY 0.617021 (11075 4814);
PAINT ORANGE (11075 4814);
WIRE 16 2175 (7425 4675)(8100 4675);
WIRE 16 2175 (7425 4675)(7425 4250);
WIRE 16 2175 (8100 4675)(8100 4250);
WIRE 16 2175 (7425 4250)(8100 4250);
WIRE 16 -1 (10200 4550)(10900 4550);
FORCEPROP 2 LAST SIG_NAME NC_PVNN_PCH_PH1_P31
J 0
(10292 4560);
DISPLAY 0.617021 (10292 4560);
PAINT ORANGE (10292 4560);
FORCEPROP 2 LASTPROP $XRERR UNIQUE?
J 0
(10930 4550);
DISPLAY 0.638298 (10930 4550);
PAINT MONO (10930 4550);
DISPLAY INVISIBLE (10930 4550);
DOT 1 (12275 2250);
DOT 1 (12550 2250);
DOT 1 (10800 2250);
DOT 1 (10375 1950);
DOT 1 (8975 2300);
DOT 1 (6850 3050);
DOT 1 (10375 2000);
DOT 1 (10375 2050);
DOT 1 (9125 2850);
DOT 1 (9050 3000);
DOT 1 (8375 3275);
DOT 1 (10375 3800);
DOT 1 (8975 4050);
DOT 1 (5600 2475);
DOT 1 (5600 3000);
DOT 1 (5850 2475);
DOT 1 (6100 2475);
DOT 1 (5850 3000);
DOT 1 (6100 3000);
DOT 1 (7000 850);
DOT 1 (6350 2475);
DOT 1 (6575 2475);
DOT 1 (6350 3000);
DOT 1 (6575 3000);
DOT 1 (6850 2475);
DOT 1 (7550 2475);
DOT 1 (7550 3275);
DOT 1 (5575 4225);
DOT 1 (5575 4700);
DOT 1 (5825 4225);
DOT 1 (6075 4225);
DOT 1 (5825 4700);
DOT 1 (6050 4700);
DOT 1 (6550 4225);
DOT 1 (6300 4700);
DOT 1 (6550 4700);
DOT 1 (6925 4225);
DOT 1 (6925 4800);
DOT 1 (7625 4225);
DOT 1 (7625 5025);
DOT 1 (7750 5025);
DOT 1 (8925 1175);
DOT 1 (9550 1175);
DOT 1 (11500 1875);
DOT 1 (11775 1875);
DOT 1 (12225 1450);
DOT 1 (12025 1875);
DOT 1 (12275 1875);
DOT 1 (10375 3700);
DOT 1 (10375 3750);
DOT 1 (11350 3950);
DOT 1 (11575 3950);
DOT 1 (11875 3575);
DOT 1 (12175 3575);
DOT 1 (12175 3950);
DOT 1 (8375 5025);
DOT 1 (9075 4600);
DOT 1 (8900 4700);
DOT 1 (12450 3575);
DOT 1 (12450 3950);
DOT 1 (12700 3950);
DOT 1 (11500 2250);
DOT 1 (10750 2700);
DOT 1 (11775 2250);
DOT 1 (10750 3950);
DOT 1 (7700 3275);
DOT 1 (11875 3950);
DOT 1 (7000 1300);
DOT 1 (6300 4225);
DOT 1 (12025 2250);
DOT 1 (10775 4425);
DOT 1 (11375 2250);
FORCENOTE
PLACE ON TOP
(7420 4275) 0;
DISPLAY LEFT (7420 4275);
DISPLAY 1.553191 (7420 4275);
PAINT PURPLE (7420 4275);
FORCENOTE
P1V05_PCH_STBY_VOLTAGE SENSE
(5805 755) 0;
DISPLAY LEFT (5805 755);
PAINT PURPLE (5805 755);
FORCENOTE
5MIL SPACING
(6530 955) 0;
DISPLAY LEFT (6530 955);
DISPLAY 0.808511 (6530 955);
PAINT PURPLE (6530 955);
FORCENOTE
PVNN_PCH_STBY_VOLTAGE SENSE
(8155 605) 0;
DISPLAY LEFT (8155 605);
PAINT PURPLE (8155 605);
FORCENOTE
ROUTE AS DIFF PAIR
(6480 1105) 0;
DISPLAY LEFT (6480 1105);
DISPLAY 0.808511 (6480 1105);
PAINT PURPLE (6480 1105);
FORCENOTE
10MIL WIDTH
(6555 1005) 0;
DISPLAY LEFT (6555 1005);
DISPLAY 0.808511 (6555 1005);
PAINT PURPLE (6555 1005);
FORCENOTE
PLACE NEAR PCH EDGE
(7780 1030) 0;
DISPLAY LEFT (7780 1030);
DISPLAY 0.808511 (7780 1030);
PAINT PURPLE (7780 1030);
FORCENOTE
ROOM= PVNN_PCH_STBY
(9527 4981) 0;
DISPLAY LEFT (9527 4981);
DISPLAY 1.595745 (9527 4981);
PAINT PURPLE (9527 4981);
FORCENOTE
PCH SIDE
(7955 1105) 0;
DISPLAY LEFT (7955 1105);
PAINT PURPLE (7955 1105);
FORCENOTE
SPOF
(6296 2026) 0;
DISPLAY LEFT (6296 2026);
DISPLAY 2.340426 (6296 2026);
PAINT PURPLE (6296 2026);
FORCENOTE
SPOF
(8721 1376) 0;
DISPLAY LEFT (8721 1376);
DISPLAY 2.340426 (8721 1376);
PAINT PURPLE (8721 1376);
FORCENOTE
ROOM= P1V05_PCH_STBY_VR
(8352 1581) 0;
DISPLAY LEFT (8352 1581);
DISPLAY 1.595745 (8352 1581);
PAINT PURPLE (8352 1581);
FORCENOTE
SPOF
(7096 3451) 0;
DISPLAY LEFT (7096 3451);
DISPLAY 2.340426 (7096 3451);
PAINT PURPLE (7096 3451);
FORCENOTE
TP FAB1 CO-LAY WITH TI PARTS 11/16
(7625 3575) 0;
DISPLAY LEFT (7625 3575);
DISPLAY 0.851064 (7625 3575);
PAINT RED (7625 3575);
FORCENOTE
TP FAB1 CO-LAY WITH TI PARTS 11/16
(7625 1775) 0;
DISPLAY LEFT (7625 1775);
DISPLAY 0.851064 (7625 1775);
PAINT RED (7625 1775);
FORCENOTE
TP FAB1 CO-LAY WITH TI PARTS 11/16
(11225 4125) 0;
DISPLAY LEFT (11225 4125);
DISPLAY 0.851064 (11225 4125);
PAINT RED (11225 4125);
FORCENOTE
VR CONTROLLER SIDE
(10030 1080) 0;
DISPLAY LEFT (10030 1080);
PAINT PURPLE (10030 1080);
FORCENOTE
TP FAB1 CO-LAY WITH TI PARTS 11/16
(11025 3400) 0;
DISPLAY LEFT (11025 3400);
DISPLAY 0.851064 (11025 3400);
PAINT RED (11025 3400);
FORCENOTE
TP FAB1 3.01 OHM NEED CHANGE TO 2.2 OHM BUT WAIT FOR SYMBOL
(11025 3350) 0;
DISPLAY LEFT (11025 3350);
DISPLAY 0.851064 (11025 3350);
PAINT RED (11025 3350);
FORCENOTE
PLACE ON TOP
(7270 2550) 0;
DISPLAY LEFT (7270 2550);
DISPLAY 1.553191 (7270 2550);
PAINT PURPLE (7270 2550);
FORCENOTE
TP FAB1 3.01 OHM NEED CHANGE TO 2.2 OHM BUT WAIT FOR SYMBOL
(11075 1700) 0;
DISPLAY LEFT (11075 1700);
DISPLAY 0.851064 (11075 1700);
PAINT RED (11075 1700);
FORCENOTE
TP FAB1 CO-LAY WITH TI PARTS 11/16
(11075 1750) 0;
DISPLAY LEFT (11075 1750);
DISPLAY 0.851064 (11075 1750);
PAINT RED (11075 1750);
FORCENOTE
TP FAB1 CO-LAY WITH TI PARTS 11/16
(11075 2400) 0;
DISPLAY LEFT (11075 2400);
DISPLAY 0.851064 (11075 2400);
PAINT RED (11075 2400);
QUIT
